FILE_TYPE = MACRO_DRAWING;
SET COLOR_WIRE YELLOW;
SET COLOR_PROP ORANGE;
SET COLOR_DOT WHITE;
SET COLOR_ARC YELLOW;
SET COLOR_BODY GREEN;
SET COLOR_NOTE PURPLE;
SET PROP_DISPLAY VALUE;
SET PAGE_NUMBER P311;
FORCEADD OFFPAGE..2
(775 2325);
FORCEPROP 2 LAST $XR0 122 
J 0
(964 2325);
DISPLAY 0.638298 (964 2325);
PAINT MONO (964 2325);
FORCEPROP 1 LAST OFFPAGE TRUE
J 0
(1100 2200);
DISPLAY 1.170213 (1100 2200);
PAINT GREEN (1100 2200);
DISPLAY INVISIBLE (1100 2200);
FORCEPROP 1 LAST COMMENT_BODY TRUE
J 0
(730 2230);
DISPLAY 1.170213 (730 2230);
PAINT GREEN (730 2230);
DISPLAY INVISIBLE (730 2230);
FORCEPROP 2 LAST CDS_LIB standard
J 0
(775 2325);
DISPLAY INVISIBLE (775 2325);
FORCEPROP 2 LAST PATH I1
J 0
(975 2375);
DISPLAY 1.021277 (975 2375);
DISPLAY INVISIBLE (975 2375);
FORCEADD OFFPAGE..2
(950 3275);
FORCEPROP 2 LAST $XR1 219 
J 0
(1259 3275);
DISPLAY 0.638298 (1259 3275);
PAINT MONO (1259 3275);
FORCEPROP 2 LAST $XR0 124 
J 0
(1139 3275);
DISPLAY 0.638298 (1139 3275);
PAINT MONO (1139 3275);
FORCEPROP 2 LAST PATH I10
J 0
(1275 3325);
DISPLAY 1.021277 (1275 3325);
DISPLAY INVISIBLE (1275 3325);
FORCEPROP 2 LAST CDS_LIB standard
J 0
(950 3275);
DISPLAY INVISIBLE (950 3275);
FORCEPROP 1 LAST OFFPAGE TRUE
J 0
(1275 3150);
DISPLAY 1.170213 (1275 3150);
PAINT GREEN (1275 3150);
DISPLAY INVISIBLE (1275 3150);
FORCEPROP 1 LAST COMMENT_BODY TRUE
J 0
(905 3180);
DISPLAY 1.170213 (905 3180);
PAINT GREEN (905 3180);
DISPLAY INVISIBLE (905 3180);
FORCEADD OFFPAGE..5
R 2
(950 3225);
FORCEPROP 2 LAST $XR1 219 
J 0
(1259 3225);
DISPLAY 0.638298 (1259 3225);
PAINT MONO (1259 3225);
FORCEPROP 2 LAST $XR0 125 
J 0
(1139 3225);
DISPLAY 0.638298 (1139 3225);
PAINT MONO (1139 3225);
FORCEPROP 2 LAST PATH I14
J 0
(1275 3275);
DISPLAY 1.021277 (1275 3275);
DISPLAY INVISIBLE (1275 3275);
FORCEPROP 1 LAST COMMENT_BODY TRUE
J 2
(850 3150);
DISPLAY 1.170213 (850 3150);
PAINT GREEN (850 3150);
DISPLAY INVISIBLE (850 3150);
FORCEPROP 1 LAST OFFPAGE TRUE
J 2
(625 3100);
DISPLAY 0.872340 (625 3100);
DISPLAY INVISIBLE (625 3100);
FORCEPROP 2 LAST CDS_LIB standard
J 2
(950 3225);
DISPLAY INVISIBLE (950 3225);
FORCEADD OFFPAGE..5
R 2
(950 3125);
FORCEPROP 2 LAST $XR1 219 
J 0
(1259 3125);
DISPLAY 0.638298 (1259 3125);
PAINT MONO (1259 3125);
FORCEPROP 2 LAST $XR0 125 
J 0
(1139 3125);
DISPLAY 0.638298 (1139 3125);
PAINT MONO (1139 3125);
FORCEPROP 2 LAST PATH I15
J 0
(1275 3175);
DISPLAY 1.021277 (1275 3175);
DISPLAY INVISIBLE (1275 3175);
FORCEPROP 1 LAST COMMENT_BODY TRUE
J 2
(850 3050);
DISPLAY 1.170213 (850 3050);
PAINT GREEN (850 3050);
DISPLAY INVISIBLE (850 3050);
FORCEPROP 1 LAST OFFPAGE TRUE
J 2
(625 3000);
DISPLAY 0.872340 (625 3000);
DISPLAY INVISIBLE (625 3000);
FORCEPROP 2 LAST CDS_LIB standard
J 2
(950 3125);
DISPLAY INVISIBLE (950 3125);
FORCEADD OFFPAGE..2
(950 3175);
FORCEPROP 2 LAST $XR1 219 
J 0
(1259 3175);
DISPLAY 0.638298 (1259 3175);
PAINT MONO (1259 3175);
FORCEPROP 2 LAST $XR0 125 
J 0
(1139 3175);
DISPLAY 0.638298 (1139 3175);
PAINT MONO (1139 3175);
FORCEPROP 2 LAST PATH I16
J 0
(1275 3225);
DISPLAY 1.021277 (1275 3225);
DISPLAY INVISIBLE (1275 3225);
FORCEPROP 2 LAST CDS_LIB standard
J 0
(950 3175);
DISPLAY INVISIBLE (950 3175);
FORCEPROP 1 LAST COMMENT_BODY TRUE
J 0
(905 3080);
DISPLAY 1.170213 (905 3080);
PAINT GREEN (905 3080);
DISPLAY INVISIBLE (905 3080);
FORCEPROP 1 LAST OFFPAGE TRUE
J 0
(1275 3050);
DISPLAY 1.170213 (1275 3050);
PAINT GREEN (1275 3050);
DISPLAY INVISIBLE (1275 3050);
FORCEADD OFFPAGE..5
R 2
(950 3075);
FORCEPROP 2 LAST $XR1 219 
J 0
(1259 3075);
DISPLAY 0.638298 (1259 3075);
PAINT MONO (1259 3075);
FORCEPROP 2 LAST $XR0 125 
J 0
(1139 3075);
DISPLAY 0.638298 (1139 3075);
PAINT MONO (1139 3075);
FORCEPROP 2 LAST PATH I17
J 0
(1275 3125);
DISPLAY 1.021277 (1275 3125);
DISPLAY INVISIBLE (1275 3125);
FORCEPROP 1 LAST COMMENT_BODY TRUE
J 2
(850 3000);
DISPLAY 1.170213 (850 3000);
PAINT GREEN (850 3000);
DISPLAY INVISIBLE (850 3000);
FORCEPROP 1 LAST OFFPAGE TRUE
J 2
(625 2950);
DISPLAY 0.872340 (625 2950);
DISPLAY INVISIBLE (625 2950);
FORCEPROP 2 LAST CDS_LIB standard
J 2
(950 3075);
DISPLAY INVISIBLE (950 3075);
FORCEADD OFFPAGE..5
R 2
(775 2375);
FORCEPROP 2 LAST $XR0 122 
J 0
(964 2375);
DISPLAY 0.638298 (964 2375);
PAINT MONO (964 2375);
FORCEPROP 1 LAST OFFPAGE TRUE
J 2
(450 2250);
DISPLAY 0.872340 (450 2250);
DISPLAY INVISIBLE (450 2250);
FORCEPROP 1 LAST COMMENT_BODY TRUE
J 2
(675 2300);
DISPLAY 1.170213 (675 2300);
PAINT GREEN (675 2300);
DISPLAY INVISIBLE (675 2300);
FORCEPROP 2 LAST CDS_LIB standard
J 2
(775 2375);
DISPLAY INVISIBLE (775 2375);
FORCEPROP 2 LAST PATH I18
J 0
(975 2425);
DISPLAY 1.021277 (975 2425);
DISPLAY INVISIBLE (975 2425);
FORCEADD OFFPAGE..2
(775 2225);
FORCEPROP 2 LAST $XR0 121 
J 0
(964 2225);
DISPLAY 0.638298 (964 2225);
PAINT MONO (964 2225);
FORCEPROP 1 LAST OFFPAGE TRUE
J 0
(1100 2100);
DISPLAY 1.170213 (1100 2100);
PAINT GREEN (1100 2100);
DISPLAY INVISIBLE (1100 2100);
FORCEPROP 1 LAST COMMENT_BODY TRUE
J 0
(730 2130);
DISPLAY 1.170213 (730 2130);
PAINT GREEN (730 2130);
DISPLAY INVISIBLE (730 2130);
FORCEPROP 2 LAST CDS_LIB standard
J 0
(775 2225);
DISPLAY INVISIBLE (775 2225);
FORCEPROP 2 LAST PATH I19
J 0
(975 2275);
DISPLAY 1.021277 (975 2275);
DISPLAY INVISIBLE (975 2275);
FORCEADD OFFPAGE..2
(775 2275);
FORCEPROP 2 LAST $XR0 121 
J 0
(964 2275);
DISPLAY 0.638298 (964 2275);
PAINT MONO (964 2275);
FORCEPROP 1 LAST OFFPAGE TRUE
J 0
(1100 2150);
DISPLAY 1.170213 (1100 2150);
PAINT GREEN (1100 2150);
DISPLAY INVISIBLE (1100 2150);
FORCEPROP 1 LAST COMMENT_BODY TRUE
J 0
(730 2180);
DISPLAY 1.170213 (730 2180);
PAINT GREEN (730 2180);
DISPLAY INVISIBLE (730 2180);
FORCEPROP 2 LAST CDS_LIB standard
J 0
(775 2275);
DISPLAY INVISIBLE (775 2275);
FORCEPROP 2 LAST PATH I2
J 0
(975 2325);
DISPLAY 1.021277 (975 2325);
DISPLAY INVISIBLE (975 2325);
FORCEADD OFFPAGE..2
(800 1975);
FORCEPROP 2 LAST $XR1 219 
J 0
(1109 1975);
DISPLAY 0.638298 (1109 1975);
PAINT MONO (1109 1975);
FORCEPROP 2 LAST $XR0 124 
J 0
(989 1975);
DISPLAY 0.638298 (989 1975);
PAINT MONO (989 1975);
FORCEPROP 1 LAST OFFPAGE TRUE
J 0
(1125 1850);
DISPLAY 1.170213 (1125 1850);
PAINT GREEN (1125 1850);
DISPLAY INVISIBLE (1125 1850);
FORCEPROP 1 LAST COMMENT_BODY TRUE
J 0
(755 1880);
DISPLAY 1.170213 (755 1880);
PAINT GREEN (755 1880);
DISPLAY INVISIBLE (755 1880);
FORCEPROP 2 LAST CDS_LIB standard
J 0
(800 1975);
DISPLAY INVISIBLE (800 1975);
FORCEPROP 2 LAST PATH I20
J 0
(1125 2025);
DISPLAY 1.021277 (1125 2025);
DISPLAY INVISIBLE (1125 2025);
FORCEADD OFFPAGE..1
R 2
(775 2025);
FORCEPROP 2 LAST $XR0 226 
J 0
(961 2025);
DISPLAY 0.638298 (961 2025);
PAINT MONO (961 2025);
FORCEPROP 2 LAST PATH I21
J 0
(975 2075);
DISPLAY 1.021277 (975 2075);
DISPLAY INVISIBLE (975 2075);
FORCEPROP 1 LAST OFFPAGE TRUE
J 2
(450 1900);
DISPLAY 0.872340 (450 1900);
DISPLAY INVISIBLE (450 1900);
FORCEPROP 1 LAST COMMENT_BODY TRUE
J 2
(650 1925);
DISPLAY 1.170213 (650 1925);
PAINT GREEN (650 1925);
DISPLAY INVISIBLE (650 1925);
FORCEPROP 2 LAST CDS_LIB standard
J 2
(775 2025);
DISPLAY INVISIBLE (775 2025);
FORCEADD OFFPAGE..2
(775 2075);
FORCEPROP 2 LAST $XR0 123 
J 0
(964 2075);
DISPLAY 0.638298 (964 2075);
PAINT MONO (964 2075);
FORCEPROP 2 LAST CDS_LIB standard
J 0
(775 2075);
DISPLAY INVISIBLE (775 2075);
FORCEPROP 1 LAST COMMENT_BODY TRUE
J 0
(730 1980);
DISPLAY 1.170213 (730 1980);
PAINT GREEN (730 1980);
DISPLAY INVISIBLE (730 1980);
FORCEPROP 1 LAST OFFPAGE TRUE
J 0
(1100 1950);
DISPLAY 1.170213 (1100 1950);
PAINT GREEN (1100 1950);
DISPLAY INVISIBLE (1100 1950);
FORCEPROP 2 LAST PATH I22
J 0
(975 2125);
DISPLAY 1.021277 (975 2125);
DISPLAY INVISIBLE (975 2125);
FORCEADD OFFPAGE..2
(775 2125);
FORCEPROP 2 LAST $XR0 223 
J 0
(964 2125);
DISPLAY 0.638298 (964 2125);
PAINT MONO (964 2125);
FORCEPROP 2 LAST CDS_LIB standard
J 0
(775 2125);
DISPLAY INVISIBLE (775 2125);
FORCEPROP 1 LAST OFFPAGE TRUE
J 0
(1100 2000);
DISPLAY 1.170213 (1100 2000);
PAINT GREEN (1100 2000);
DISPLAY INVISIBLE (1100 2000);
FORCEPROP 1 LAST COMMENT_BODY TRUE
J 0
(730 2030);
DISPLAY 1.170213 (730 2030);
PAINT GREEN (730 2030);
DISPLAY INVISIBLE (730 2030);
FORCEPROP 2 LAST PATH I23
J 0
(975 2175);
DISPLAY 1.021277 (975 2175);
DISPLAY INVISIBLE (975 2175);
FORCEADD OFFPAGE..1
R 2
(775 2175);
FORCEPROP 2 LAST $XR0 226 
J 0
(961 2175);
DISPLAY 0.638298 (961 2175);
PAINT MONO (961 2175);
FORCEPROP 2 LAST CDS_LIB standard
J 0
(775 2175);
PAINT MONO (775 2175);
DISPLAY INVISIBLE (775 2175);
FORCEPROP 2 LAST PATH I24
J 0
(975 2225);
DISPLAY 1.021277 (975 2225);
DISPLAY INVISIBLE (975 2225);
FORCEPROP 1 LAST COMMENT_BODY TRUE
J 2
(650 2075);
DISPLAY 1.170213 (650 2075);
PAINT GREEN (650 2075);
DISPLAY INVISIBLE (650 2075);
FORCEPROP 1 LAST OFFPAGE TRUE
J 2
(450 2050);
DISPLAY 1.170213 (450 2050);
PAINT GREEN (450 2050);
DISPLAY INVISIBLE (450 2050);
FORCEADD OFFPAGE..2
(800 1925);
FORCEPROP 2 LAST $XR1 219 
J 0
(1109 1925);
DISPLAY 0.638298 (1109 1925);
PAINT MONO (1109 1925);
FORCEPROP 2 LAST $XR0 125 
J 0
(989 1925);
DISPLAY 0.638298 (989 1925);
PAINT MONO (989 1925);
FORCEPROP 1 LAST OFFPAGE TRUE
J 0
(1125 1800);
DISPLAY 1.170213 (1125 1800);
PAINT GREEN (1125 1800);
DISPLAY INVISIBLE (1125 1800);
FORCEPROP 1 LAST COMMENT_BODY TRUE
J 0
(755 1830);
DISPLAY 1.170213 (755 1830);
PAINT GREEN (755 1830);
DISPLAY INVISIBLE (755 1830);
FORCEPROP 2 LAST CDS_LIB standard
J 0
(800 1925);
DISPLAY INVISIBLE (800 1925);
FORCEPROP 2 LAST PATH I25
J 0
(1125 1975);
DISPLAY 1.021277 (1125 1975);
DISPLAY INVISIBLE (1125 1975);
FORCEADD OFFPAGE..5
R 2
(800 1875);
FORCEPROP 2 LAST $XR1 219 
J 0
(1109 1875);
DISPLAY 0.638298 (1109 1875);
PAINT MONO (1109 1875);
FORCEPROP 2 LAST $XR0 124 
J 0
(989 1875);
DISPLAY 0.638298 (989 1875);
PAINT MONO (989 1875);
FORCEPROP 1 LAST OFFPAGE TRUE
J 2
(475 1750);
DISPLAY 0.872340 (475 1750);
DISPLAY INVISIBLE (475 1750);
FORCEPROP 1 LAST COMMENT_BODY TRUE
J 2
(700 1800);
DISPLAY 1.170213 (700 1800);
PAINT GREEN (700 1800);
DISPLAY INVISIBLE (700 1800);
FORCEPROP 2 LAST CDS_LIB standard
J 2
(800 1875);
DISPLAY INVISIBLE (800 1875);
FORCEPROP 2 LAST PATH I26
J 0
(1125 1925);
DISPLAY 1.021277 (1125 1925);
DISPLAY INVISIBLE (1125 1925);
FORCEADD OFFPAGE..2
(800 1825);
FORCEPROP 2 LAST $XR1 219 
J 0
(1109 1825);
DISPLAY 0.638298 (1109 1825);
PAINT MONO (1109 1825);
FORCEPROP 2 LAST $XR0 125 
J 0
(989 1825);
DISPLAY 0.638298 (989 1825);
PAINT MONO (989 1825);
FORCEPROP 1 LAST COMMENT_BODY TRUE
J 0
(755 1730);
DISPLAY 1.170213 (755 1730);
PAINT GREEN (755 1730);
DISPLAY INVISIBLE (755 1730);
FORCEPROP 1 LAST OFFPAGE TRUE
J 0
(1125 1700);
DISPLAY 1.170213 (1125 1700);
PAINT GREEN (1125 1700);
DISPLAY INVISIBLE (1125 1700);
FORCEPROP 2 LAST CDS_LIB standard
J 0
(800 1825);
DISPLAY INVISIBLE (800 1825);
FORCEPROP 2 LAST PATH I27
J 0
(1125 1875);
DISPLAY 1.021277 (1125 1875);
DISPLAY INVISIBLE (1125 1875);
FORCEADD UNIVERSAL_POWER..1
(1300 350);
FORCEPROP 3 LASTPIN (1300 300) SIG_NAME P3V3_AUX\g
J 0
(1310 310);
DISPLAY 0.659574 (1310 310);
PAINT MONO (1310 310);
DISPLAY INVISIBLE (1310 310);
FORCEPROP 1 LAST HDL_POWER P3V3_AUX
J 1
(1300 400);
DISPLAY 0.872340 (1300 400);
PAINT GREEN (1300 400);
FORCEPROP 1 LAST PATH I28
J 0
(1350 375);
DISPLAY 0.872340 (1350 375);
PAINT AQUA (1350 375);
DISPLAY INVISIBLE (1350 375);
FORCEPROP 2 LAST CDS_LIB logical_power
J 0
(1300 350);
DISPLAY INVISIBLE (1300 350);
FORCEADD Q_RES..2
(1300 50);
FORCEPROP 1 LAST PART_NUMBER CS31002FB08
J 0
(1340 -125);
DISPLAY 0.510638 (1340 -125);
DISPLAY INVISIBLE (1340 -125);
FORCEPROP 1 LAST PACK_TYPE 0402LF
J 0
(1340 -75);
DISPLAY 0.510638 (1340 -75);
FORCEPROP 1 LAST VALUE 10K
J 0
(1345 125);
DISPLAY 0.510638 (1345 125);
FORCEPROP 1 LAST WATTAGE 1/16W
J 0
(1340 25);
DISPLAY 0.510638 (1340 25);
FORCEPROP 1 LAST TOLERANCE 1%
J 0
(1345 75);
DISPLAY 0.510638 (1345 75);
FORCEPROP 1 LAST MATERIAL CHIP
J 0
(1340 -25);
DISPLAY 0.510638 (1340 -25);
FORCEPROP 1 LAST $LOCATION R3249
J 0
(1345 175);
DISPLAY 0.978723 (1345 175);
FORCEPROP 1 LASTPIN (1300 150) $PN 1
J 0
(1305 112);
DISPLAY 0.787234 (1305 112);
PAINT MONO (1305 112);
FORCEPROP 1 LASTPIN (1300 -50) $PN 2
J 0
(1305 -40);
DISPLAY 0.787234 (1305 -40);
PAINT MONO (1305 -40);
FORCEPROP 1 LAST PATH I29
J 0
(1350 225);
DISPLAY 0.978723 (1350 225);
PAINT WHITE (1350 225);
DISPLAY INVISIBLE (1350 225);
FORCEPROP 2 LAST CDS_LIB pure_quanta
J 0
(1300 50);
DISPLAY INVISIBLE (1300 50);
FORCEPROP 0 LAST CDS_LOCATION R3249
J 0
(1350 225);
DISPLAY 1.021277 (1350 225);
DISPLAY INVISIBLE (1350 225);
FORCEPROP 0 LAST $SEC 1
J 0
(1350 225);
DISPLAY 0.680851 (1350 225);
PAINT MONO (1350 225);
DISPLAY INVISIBLE (1350 225);
FORCEPROP 0 LAST CDS_SEC 1
J 0
(1350 225);
DISPLAY 1.021277 (1350 225);
DISPLAY INVISIBLE (1350 225);
FORCEADD UNIVERSAL_POWER..1
(4175 3575);
FORCEPROP 3 LASTPIN (4175 3525) SIG_NAME P3V3_AUX\g
J 0
(4185 3535);
DISPLAY 0.659574 (4185 3535);
PAINT MONO (4185 3535);
DISPLAY INVISIBLE (4185 3535);
FORCEPROP 1 LAST HDL_POWER P3V3_AUX
J 1
(4175 3625);
DISPLAY 0.872340 (4175 3625);
PAINT GREEN (4175 3625);
FORCEPROP 2 LAST CDS_LIB logical_power
J 0
(4175 3575);
PAINT MONO (4175 3575);
DISPLAY INVISIBLE (4175 3575);
FORCEPROP 1 LAST PATH I3
J 0
(4225 3600);
DISPLAY 0.872340 (4225 3600);
PAINT AQUA (4225 3600);
DISPLAY INVISIBLE (4225 3600);
FORCEADD OFFPAGE..5
R 2
(875 25);
FORCEPROP 2 LAST $XR1 221 
J 0
(1184 25);
DISPLAY 0.638298 (1184 25);
PAINT MONO (1184 25);
FORCEPROP 2 LAST $XR0 220 
J 0
(1064 25);
DISPLAY 0.638298 (1064 25);
PAINT MONO (1064 25);
FORCEPROP 1 LAST OFFPAGE TRUE
J 2
(550 -100);
DISPLAY 0.872340 (550 -100);
DISPLAY INVISIBLE (550 -100);
FORCEPROP 1 LAST COMMENT_BODY TRUE
J 2
(775 -50);
DISPLAY 1.170213 (775 -50);
PAINT GREEN (775 -50);
DISPLAY INVISIBLE (775 -50);
FORCEPROP 2 LAST PATH I30
J 0
(1250 75);
DISPLAY 1.021277 (1250 75);
DISPLAY INVISIBLE (1250 75);
FORCEPROP 2 LAST CDS_LIB standard
J 2
(875 25);
PAINT MONO (875 25);
DISPLAY INVISIBLE (875 25);
FORCEADD OFFPAGE..1
R 2
(875 -75);
FORCEPROP 2 LAST $XR0 221 
J 0
(1061 -75);
DISPLAY 0.638298 (1061 -75);
PAINT MONO (1061 -75);
FORCEPROP 1 LAST COMMENT_BODY TRUE
J 2
(750 -175);
DISPLAY 1.170213 (750 -175);
PAINT GREEN (750 -175);
DISPLAY INVISIBLE (750 -175);
FORCEPROP 1 LAST OFFPAGE TRUE
J 2
(550 -200);
DISPLAY 0.872340 (550 -200);
DISPLAY INVISIBLE (550 -200);
FORCEPROP 2 LAST PATH I31
J 0
(1250 -25);
DISPLAY 1.021277 (1250 -25);
DISPLAY INVISIBLE (1250 -25);
FORCEPROP 2 LAST CDS_LIB standard
J 2
(875 -75);
PAINT MONO (875 -75);
DISPLAY INVISIBLE (875 -75);
FORCEADD OFFPAGE..1
R 2
(875 -25);
FORCEPROP 2 LAST $XR0 221 
J 0
(1061 -25);
DISPLAY 0.638298 (1061 -25);
PAINT MONO (1061 -25);
FORCEPROP 2 LAST PATH I32
J 0
(1250 25);
DISPLAY 1.021277 (1250 25);
DISPLAY INVISIBLE (1250 25);
FORCEPROP 1 LAST COMMENT_BODY TRUE
J 2
(750 -125);
DISPLAY 1.170213 (750 -125);
PAINT GREEN (750 -125);
DISPLAY INVISIBLE (750 -125);
FORCEPROP 1 LAST OFFPAGE TRUE
J 2
(550 -150);
DISPLAY 0.872340 (550 -150);
DISPLAY INVISIBLE (550 -150);
FORCEPROP 2 LAST CDS_LIB standard
J 2
(875 -25);
PAINT MONO (875 -25);
DISPLAY INVISIBLE (875 -25);
FORCEADD LCMXO3LF9400C5BG484C..1
(-875 2075);
FORCEPROP 1 LAST PART_NUMBER AJ094000T08
J 0
(-1376 3615);
DISPLAY 0.723404 (-1376 3615);
PAINT GREEN (-1376 3615);
DISPLAY INVISIBLE (-1376 3615);
FORCEPROP 2 LAST VALUE LCMXO3LF-9400C-5BG484C
J 0
(-1375 3800);
DISPLAY 1.021277 (-1375 3800);
FORCEPROP 2 LAST PART_TYPE SMLF
J 0
(-1375 3850);
DISPLAY 1.021277 (-1375 3850);
FORCEPROP 1 LAST MATERIAL IC
J 0
(-1376 3488);
DISPLAY 0.723404 (-1376 3488);
PAINT GREEN (-1376 3488);
FORCEPROP 1 LAST $LOCATION U249
J 0
(-1376 3762);
DISPLAY 0.723404 (-1376 3762);
PAINT GREEN (-1376 3762);
FORCEPROP 0 LASTPIN (-1525 3425) $PN D3
J 2
(-1535 3435);
DISPLAY 0.680851 (-1535 3435);
PAINT MONO (-1535 3435);
FORCEPROP 0 LASTPIN (-1525 3375) $PN D4
J 2
(-1535 3385);
DISPLAY 0.680851 (-1535 3385);
PAINT MONO (-1535 3385);
FORCEPROP 0 LASTPIN (-1525 3325) $PN F6
J 2
(-1535 3335);
DISPLAY 0.680851 (-1535 3335);
PAINT MONO (-1535 3335);
FORCEPROP 0 LASTPIN (-1525 3275) $PN G7
J 2
(-1535 3285);
DISPLAY 0.680851 (-1535 3285);
PAINT MONO (-1535 3285);
FORCEPROP 0 LASTPIN (-1525 3225) $PN E4
J 2
(-1535 3235);
DISPLAY 0.680851 (-1535 3235);
PAINT MONO (-1535 3235);
FORCEPROP 0 LASTPIN (-1525 3175) $PN F5
J 2
(-1535 3185);
DISPLAY 0.680851 (-1535 3185);
PAINT MONO (-1535 3185);
FORCEPROP 0 LASTPIN (-1525 3125) $PN G6
J 2
(-1535 3135);
DISPLAY 0.680851 (-1535 3135);
PAINT MONO (-1535 3135);
FORCEPROP 0 LASTPIN (-1525 3075) $PN H7
J 2
(-1535 3085);
DISPLAY 0.680851 (-1535 3085);
PAINT MONO (-1535 3085);
FORCEPROP 0 LASTPIN (-1525 3025) $PN C1
J 2
(-1535 3035);
DISPLAY 0.680851 (-1535 3035);
PAINT MONO (-1535 3035);
FORCEPROP 0 LASTPIN (-1525 2975) $PN D2
J 2
(-1535 2985);
DISPLAY 0.680851 (-1535 2985);
PAINT MONO (-1535 2985);
FORCEPROP 0 LASTPIN (-1525 2925) $PN G5
J 2
(-1535 2935);
DISPLAY 0.680851 (-1535 2935);
PAINT MONO (-1535 2935);
FORCEPROP 0 LASTPIN (-1525 2875) $PN H6
J 2
(-1535 2885);
DISPLAY 0.680851 (-1535 2885);
PAINT MONO (-1535 2885);
FORCEPROP 0 LASTPIN (-1525 2825) $PN D1
J 2
(-1535 2835);
DISPLAY 0.680851 (-1535 2835);
PAINT MONO (-1535 2835);
FORCEPROP 0 LASTPIN (-1525 2775) $PN E2
J 2
(-1535 2785);
DISPLAY 0.680851 (-1535 2785);
PAINT MONO (-1535 2785);
FORCEPROP 0 LASTPIN (-1525 2725) $PN E3
J 2
(-1535 2735);
DISPLAY 0.680851 (-1535 2735);
PAINT MONO (-1535 2735);
FORCEPROP 0 LASTPIN (-1525 2675) $PN F4
J 2
(-1535 2685);
DISPLAY 0.680851 (-1535 2685);
PAINT MONO (-1535 2685);
FORCEPROP 0 LASTPIN (-1525 2625) $PN E1
J 2
(-1535 2635);
DISPLAY 0.680851 (-1535 2635);
PAINT MONO (-1535 2635);
FORCEPROP 0 LASTPIN (-1525 2575) $PN F1
J 2
(-1535 2585);
DISPLAY 0.680851 (-1535 2585);
PAINT MONO (-1535 2585);
FORCEPROP 0 LASTPIN (-1525 2525) $PN G3
J 2
(-1535 2535);
DISPLAY 0.680851 (-1535 2535);
PAINT MONO (-1535 2535);
FORCEPROP 0 LASTPIN (-1525 2475) $PN G4
J 2
(-1535 2485);
DISPLAY 0.680851 (-1535 2485);
PAINT MONO (-1535 2485);
FORCEPROP 0 LASTPIN (-225 3425) $PN G2
J 0
(-215 3435);
DISPLAY 0.680851 (-215 3435);
PAINT MONO (-215 3435);
FORCEPROP 0 LASTPIN (-225 3375) $PN G1
J 0
(-215 3385);
DISPLAY 0.680851 (-215 3385);
PAINT MONO (-215 3385);
FORCEPROP 0 LASTPIN (-225 3325) $PN H4
J 0
(-215 3335);
DISPLAY 0.680851 (-215 3335);
PAINT MONO (-215 3335);
FORCEPROP 0 LASTPIN (-225 3275) $PN H3
J 0
(-215 3285);
DISPLAY 0.680851 (-215 3285);
PAINT MONO (-215 3285);
FORCEPROP 0 LASTPIN (-225 3225) $PN H2
J 0
(-215 3235);
DISPLAY 0.680851 (-215 3235);
PAINT MONO (-215 3235);
FORCEPROP 0 LASTPIN (-225 3175) $PN H1
J 0
(-215 3185);
DISPLAY 0.680851 (-215 3185);
PAINT MONO (-215 3185);
FORCEPROP 0 LASTPIN (-225 3125) $PN J7
J 0
(-215 3135);
DISPLAY 0.680851 (-215 3135);
PAINT MONO (-215 3135);
FORCEPROP 0 LASTPIN (-225 3075) $PN J6
J 0
(-215 3085);
DISPLAY 0.680851 (-215 3085);
PAINT MONO (-215 3085);
FORCEPROP 0 LASTPIN (-225 3025) $PN H5
J 0
(-215 3035);
DISPLAY 0.680851 (-215 3035);
PAINT MONO (-215 3035);
FORCEPROP 0 LASTPIN (-225 2975) $PN J5
J 0
(-215 2985);
DISPLAY 0.680851 (-215 2985);
PAINT MONO (-215 2985);
FORCEPROP 0 LASTPIN (-225 2925) $PN J4
J 0
(-215 2935);
DISPLAY 0.680851 (-215 2935);
PAINT MONO (-215 2935);
FORCEPROP 0 LASTPIN (-225 2875) $PN J3
J 0
(-215 2885);
DISPLAY 0.680851 (-215 2885);
PAINT MONO (-215 2885);
FORCEPROP 0 LASTPIN (-225 2825) $PN J2
J 0
(-215 2835);
DISPLAY 0.680851 (-215 2835);
PAINT MONO (-215 2835);
FORCEPROP 0 LASTPIN (-225 2775) $PN J1
J 0
(-215 2785);
DISPLAY 0.680851 (-215 2785);
PAINT MONO (-215 2785);
FORCEPROP 0 LASTPIN (-225 2725) $PN K7
J 0
(-215 2735);
DISPLAY 0.680851 (-215 2735);
PAINT MONO (-215 2735);
FORCEPROP 0 LASTPIN (-225 2675) $PN K6
J 0
(-215 2685);
DISPLAY 0.680851 (-215 2685);
PAINT MONO (-215 2685);
FORCEPROP 0 LASTPIN (-1525 1325) $PN L7
J 2
(-1535 1335);
DISPLAY 0.680851 (-1535 1335);
PAINT MONO (-1535 1335);
FORCEPROP 0 LASTPIN (-1525 1275) $PN K5
J 2
(-1535 1285);
DISPLAY 0.680851 (-1535 1285);
PAINT MONO (-1535 1285);
FORCEPROP 0 LASTPIN (-1525 1225) $PN K4
J 2
(-1535 1235);
DISPLAY 0.680851 (-1535 1235);
PAINT MONO (-1535 1235);
FORCEPROP 0 LASTPIN (-1525 1175) $PN K3
J 2
(-1535 1185);
DISPLAY 0.680851 (-1535 1185);
PAINT MONO (-1535 1185);
FORCEPROP 0 LASTPIN (-1525 1125) $PN K2
J 2
(-1535 1135);
DISPLAY 0.680851 (-1535 1135);
PAINT MONO (-1535 1135);
FORCEPROP 0 LASTPIN (-1525 1075) $PN K1
J 2
(-1535 1085);
DISPLAY 0.680851 (-1535 1085);
PAINT MONO (-1535 1085);
FORCEPROP 0 LASTPIN (-1525 1025) $PN L6
J 2
(-1535 1035);
DISPLAY 0.680851 (-1535 1035);
PAINT MONO (-1535 1035);
FORCEPROP 0 LASTPIN (-1525 975) $PN L5
J 2
(-1535 985);
DISPLAY 0.680851 (-1535 985);
PAINT MONO (-1535 985);
FORCEPROP 0 LASTPIN (-1525 925) $PN L1
J 2
(-1535 935);
DISPLAY 0.680851 (-1535 935);
PAINT MONO (-1535 935);
FORCEPROP 0 LASTPIN (-1525 875) $PN M2
J 2
(-1535 885);
DISPLAY 0.680851 (-1535 885);
PAINT MONO (-1535 885);
FORCEPROP 0 LASTPIN (-1525 825) $PN L3
J 2
(-1535 835);
DISPLAY 0.680851 (-1535 835);
PAINT MONO (-1535 835);
FORCEPROP 0 LASTPIN (-1525 775) $PN L4
J 2
(-1535 785);
DISPLAY 0.680851 (-1535 785);
PAINT MONO (-1535 785);
FORCEPROP 0 LASTPIN (-225 1325) $PN M1
J 0
(-215 1335);
DISPLAY 0.680851 (-215 1335);
PAINT MONO (-215 1335);
FORCEPROP 0 LASTPIN (-225 1275) $PN N1
J 0
(-215 1285);
DISPLAY 0.680851 (-215 1285);
PAINT MONO (-215 1285);
FORCEPROP 0 LASTPIN (-225 1225) $PN M6
J 0
(-215 1235);
DISPLAY 0.680851 (-215 1235);
PAINT MONO (-215 1235);
FORCEPROP 0 LASTPIN (-225 1175) $PN M5
J 0
(-215 1185);
DISPLAY 0.680851 (-215 1185);
PAINT MONO (-215 1185);
FORCEPROP 0 LASTPIN (-225 1125) $PN N2
J 0
(-215 1135);
DISPLAY 0.680851 (-215 1135);
PAINT MONO (-215 1135);
FORCEPROP 0 LASTPIN (-225 1075) $PN P1
J 0
(-215 1085);
DISPLAY 0.680851 (-215 1085);
PAINT MONO (-215 1085);
FORCEPROP 0 LASTPIN (-225 1025) $PN N3
J 0
(-215 1035);
DISPLAY 0.680851 (-215 1035);
PAINT MONO (-215 1035);
FORCEPROP 0 LASTPIN (-225 975) $PN N4
J 0
(-215 985);
DISPLAY 0.680851 (-215 985);
PAINT MONO (-215 985);
FORCEPROP 0 LASTPIN (-225 925) $PN P2
J 0
(-215 935);
DISPLAY 0.680851 (-215 935);
PAINT MONO (-215 935);
FORCEPROP 0 LASTPIN (-225 875) $PN R1
J 0
(-215 885);
DISPLAY 0.680851 (-215 885);
PAINT MONO (-215 885);
FORCEPROP 0 LASTPIN (-225 825) $PN P3
J 0
(-215 835);
DISPLAY 0.680851 (-215 835);
PAINT MONO (-215 835);
FORCEPROP 0 LASTPIN (-225 775) $PN M7
J 0
(-215 785);
DISPLAY 0.680851 (-215 785);
PAINT MONO (-215 785);
FORCEPROP 0 LASTPIN (-1525 1425) $PN P4
J 2
(-1535 1435);
DISPLAY 0.680851 (-1535 1435);
PAINT MONO (-1535 1435);
FORCEPROP 0 LASTPIN (-1525 1475) $PN N5
J 2
(-1535 1485);
DISPLAY 0.680851 (-1535 1485);
PAINT MONO (-1535 1485);
FORCEPROP 0 LASTPIN (-1525 1525) $PN N6
J 2
(-1535 1535);
DISPLAY 0.680851 (-1535 1535);
PAINT MONO (-1535 1535);
FORCEPROP 0 LASTPIN (-1525 1575) $PN N7
J 2
(-1535 1585);
DISPLAY 0.680851 (-1535 1585);
PAINT MONO (-1535 1585);
FORCEPROP 0 LASTPIN (-1525 1625) $PN R2
J 2
(-1535 1635);
DISPLAY 0.680851 (-1535 1635);
PAINT MONO (-1535 1635);
FORCEPROP 0 LASTPIN (-1525 1675) $PN T1
J 2
(-1535 1685);
DISPLAY 0.680851 (-1535 1685);
PAINT MONO (-1535 1685);
FORCEPROP 0 LASTPIN (-1525 1725) $PN P5
J 2
(-1535 1735);
DISPLAY 0.680851 (-1535 1735);
PAINT MONO (-1535 1735);
FORCEPROP 0 LASTPIN (-1525 1775) $PN P6
J 2
(-1535 1785);
DISPLAY 0.680851 (-1535 1785);
PAINT MONO (-1535 1785);
FORCEPROP 0 LASTPIN (-1525 1825) $PN R3
J 2
(-1535 1835);
DISPLAY 0.680851 (-1535 1835);
PAINT MONO (-1535 1835);
FORCEPROP 0 LASTPIN (-1525 1875) $PN R4
J 2
(-1535 1885);
DISPLAY 0.680851 (-1535 1885);
PAINT MONO (-1535 1885);
FORCEPROP 0 LASTPIN (-1525 1925) $PN R5
J 2
(-1535 1935);
DISPLAY 0.680851 (-1535 1935);
PAINT MONO (-1535 1935);
FORCEPROP 0 LASTPIN (-1525 1975) $PN P7
J 2
(-1535 1985);
DISPLAY 0.680851 (-1535 1985);
PAINT MONO (-1535 1985);
FORCEPROP 0 LASTPIN (-1525 2025) $PN T2
J 2
(-1535 2035);
DISPLAY 0.680851 (-1535 2035);
PAINT MONO (-1535 2035);
FORCEPROP 0 LASTPIN (-1525 2075) $PN U1
J 2
(-1535 2085);
DISPLAY 0.680851 (-1535 2085);
PAINT MONO (-1535 2085);
FORCEPROP 0 LASTPIN (-1525 2125) $PN R6
J 2
(-1535 2135);
DISPLAY 0.680851 (-1535 2135);
PAINT MONO (-1535 2135);
FORCEPROP 0 LASTPIN (-1525 2175) $PN R7
J 2
(-1535 2185);
DISPLAY 0.680851 (-1535 2185);
PAINT MONO (-1535 2185);
FORCEPROP 0 LASTPIN (-1525 2225) $PN T3
J 2
(-1535 2235);
DISPLAY 0.680851 (-1535 2235);
PAINT MONO (-1535 2235);
FORCEPROP 0 LASTPIN (-1525 2275) $PN T4
J 2
(-1535 2285);
DISPLAY 0.680851 (-1535 2285);
PAINT MONO (-1535 2285);
FORCEPROP 0 LASTPIN (-1525 2325) $PN T5
J 2
(-1535 2335);
DISPLAY 0.680851 (-1535 2335);
PAINT MONO (-1535 2335);
FORCEPROP 0 LASTPIN (-1525 2375) $PN T6
J 2
(-1535 2385);
DISPLAY 0.680851 (-1535 2385);
PAINT MONO (-1535 2385);
FORCEPROP 0 LASTPIN (-225 1625) $PN U2
J 0
(-215 1635);
DISPLAY 0.680851 (-215 1635);
PAINT MONO (-215 1635);
FORCEPROP 0 LASTPIN (-225 1675) $PN V1
J 0
(-215 1685);
DISPLAY 0.680851 (-215 1685);
PAINT MONO (-215 1685);
FORCEPROP 0 LASTPIN (-225 1725) $PN U3
J 0
(-215 1735);
DISPLAY 0.680851 (-215 1735);
PAINT MONO (-215 1735);
FORCEPROP 0 LASTPIN (-225 1775) $PN U4
J 0
(-215 1785);
DISPLAY 0.680851 (-215 1785);
PAINT MONO (-215 1785);
FORCEPROP 0 LASTPIN (-225 1825) $PN W1
J 0
(-215 1835);
DISPLAY 0.680851 (-215 1835);
PAINT MONO (-215 1835);
FORCEPROP 0 LASTPIN (-225 1875) $PN W2
J 0
(-215 1885);
DISPLAY 0.680851 (-215 1885);
PAINT MONO (-215 1885);
FORCEPROP 0 LASTPIN (-225 1925) $PN V4
J 0
(-215 1935);
DISPLAY 0.680851 (-215 1935);
PAINT MONO (-215 1935);
FORCEPROP 0 LASTPIN (-225 1975) $PN U5
J 0
(-215 1985);
DISPLAY 0.680851 (-215 1985);
PAINT MONO (-215 1985);
FORCEPROP 0 LASTPIN (-225 2025) $PN Y1
J 0
(-215 2035);
DISPLAY 0.680851 (-215 2035);
PAINT MONO (-215 2035);
FORCEPROP 0 LASTPIN (-225 2075) $PN AA1
J 0
(-215 2085);
DISPLAY 0.680851 (-215 2085);
PAINT MONO (-215 2085);
FORCEPROP 0 LASTPIN (-225 2125) $PN W3
J 0
(-215 2135);
DISPLAY 0.680851 (-215 2135);
PAINT MONO (-215 2135);
FORCEPROP 0 LASTPIN (-225 2175) $PN Y2
J 0
(-215 2185);
DISPLAY 0.680851 (-215 2185);
PAINT MONO (-215 2185);
FORCEPROP 0 LASTPIN (-225 2225) $PN Y3
J 0
(-215 2235);
DISPLAY 0.680851 (-215 2235);
PAINT MONO (-215 2235);
FORCEPROP 0 LASTPIN (-225 2275) $PN W4
J 0
(-215 2285);
DISPLAY 0.680851 (-215 2285);
PAINT MONO (-215 2285);
FORCEPROP 0 LASTPIN (-225 2325) $PN V5
J 0
(-215 2335);
DISPLAY 0.680851 (-215 2335);
PAINT MONO (-215 2335);
FORCEPROP 0 LASTPIN (-225 2375) $PN T7
J 0
(-215 2385);
DISPLAY 0.680851 (-215 2385);
PAINT MONO (-215 2385);
FORCEPROP 1 LAST CDS_LMAN_SYM_OUTLINE -500,1400,500,-1400
J 0
(-875 2075);
DISPLAY 0.468085 (-875 2075);
PAINT GREEN (-875 2075);
DISPLAY INVISIBLE (-875 2075);
FORCEPROP 1 LAST NEEDS_NO_SIZE TRUE
J 0
(-875 2075);
DISPLAY 0.723404 (-875 2075);
PAINT GREEN (-875 2075);
DISPLAY INVISIBLE (-875 2075);
FORCEPROP 2 LAST CDS_LIB pure_quanta
J 0
(-875 2075);
DISPLAY INVISIBLE (-875 2075);
FORCEPROP 1 LAST PATH I33
J 0
(-875 2075);
DISPLAY 0.723404 (-875 2075);
PAINT GREEN (-875 2075);
DISPLAY INVISIBLE (-875 2075);
FORCEPROP 0 LAST CDS_LOCATION U249
J 0
(-1375 3900);
DISPLAY 1.021277 (-1375 3900);
DISPLAY INVISIBLE (-1375 3900);
FORCEPROP 0 LAST $SEC 1
J 0
(-1375 3900);
DISPLAY 0.680851 (-1375 3900);
PAINT MONO (-1375 3900);
DISPLAY INVISIBLE (-1375 3900);
FORCEPROP 0 LAST CDS_SEC 1
J 0
(-1375 3900);
DISPLAY 1.021277 (-1375 3900);
DISPLAY INVISIBLE (-1375 3900);
FORCEADD OFFPAGE..1
(-2575 3425);
FORCEPROP 2 LAST $XR0 225 
J 0
(-2857 3425);
DISPLAY 0.638298 (-2857 3425);
PAINT MONO (-2857 3425);
FORCEPROP 2 LAST CDS_LIB standard
J 0
(-2575 3425);
DISPLAY INVISIBLE (-2575 3425);
FORCEPROP 1 LAST COMMENT_BODY TRUE
J 0
(-2450 3325);
DISPLAY 1.170213 (-2450 3325);
PAINT GREEN (-2450 3325);
DISPLAY INVISIBLE (-2450 3325);
FORCEPROP 1 LAST OFFPAGE TRUE
J 0
(-2250 3300);
DISPLAY 0.872340 (-2250 3300);
DISPLAY INVISIBLE (-2250 3300);
FORCEPROP 2 LAST PATH I34
J 0
(-2825 3475);
DISPLAY 1.021277 (-2825 3475);
DISPLAY INVISIBLE (-2825 3475);
FORCEADD OFFPAGE..1
(-2575 3375);
FORCEPROP 2 LAST $XR0 225 
J 0
(-2857 3375);
DISPLAY 0.638298 (-2857 3375);
PAINT MONO (-2857 3375);
FORCEPROP 1 LAST COMMENT_BODY TRUE
J 0
(-2450 3275);
DISPLAY 1.170213 (-2450 3275);
PAINT GREEN (-2450 3275);
DISPLAY INVISIBLE (-2450 3275);
FORCEPROP 1 LAST OFFPAGE TRUE
J 0
(-2250 3250);
DISPLAY 1.170213 (-2250 3250);
PAINT GREEN (-2250 3250);
DISPLAY INVISIBLE (-2250 3250);
FORCEPROP 2 LAST CDS_LIB standard
J 2
(-2575 3375);
PAINT MONO (-2575 3375);
DISPLAY INVISIBLE (-2575 3375);
FORCEPROP 2 LAST PATH I35
J 0
(-2825 3425);
DISPLAY 1.021277 (-2825 3425);
DISPLAY INVISIBLE (-2825 3425);
FORCEADD OFFPAGE..1
(-2575 3325);
FORCEPROP 2 LAST $XR0 225 
J 0
(-2857 3325);
DISPLAY 0.638298 (-2857 3325);
PAINT MONO (-2857 3325);
FORCEPROP 2 LAST CDS_LIB standard
J 0
(-2575 3325);
DISPLAY INVISIBLE (-2575 3325);
FORCEPROP 1 LAST OFFPAGE TRUE
J 0
(-2250 3200);
DISPLAY 0.872340 (-2250 3200);
DISPLAY INVISIBLE (-2250 3200);
FORCEPROP 1 LAST COMMENT_BODY TRUE
J 0
(-2450 3225);
DISPLAY 1.170213 (-2450 3225);
PAINT GREEN (-2450 3225);
DISPLAY INVISIBLE (-2450 3225);
FORCEPROP 2 LAST PATH I36
J 0
(-2825 3375);
DISPLAY 1.021277 (-2825 3375);
DISPLAY INVISIBLE (-2825 3375);
FORCEADD OFFPAGE..1
(-2575 3275);
FORCEPROP 2 LAST $XR0 225 
J 0
(-2857 3275);
DISPLAY 0.638298 (-2857 3275);
PAINT MONO (-2857 3275);
FORCEPROP 2 LAST CDS_LIB standard
J 2
(-2575 3275);
DISPLAY INVISIBLE (-2575 3275);
FORCEPROP 1 LAST COMMENT_BODY TRUE
J 0
(-2450 3175);
DISPLAY 1.170213 (-2450 3175);
PAINT GREEN (-2450 3175);
DISPLAY INVISIBLE (-2450 3175);
FORCEPROP 1 LAST OFFPAGE TRUE
J 0
(-2250 3150);
DISPLAY 1.170213 (-2250 3150);
PAINT GREEN (-2250 3150);
DISPLAY INVISIBLE (-2250 3150);
FORCEPROP 2 LAST PATH I37
J 0
(-2825 3325);
DISPLAY 1.021277 (-2825 3325);
DISPLAY INVISIBLE (-2825 3325);
FORCEADD OFFPAGE..1
(-2575 3225);
FORCEPROP 2 LAST $XR0 225 
J 0
(-2857 3225);
DISPLAY 0.638298 (-2857 3225);
PAINT MONO (-2857 3225);
FORCEPROP 2 LAST CDS_LIB standard
J 0
(-2575 3225);
DISPLAY INVISIBLE (-2575 3225);
FORCEPROP 1 LAST OFFPAGE TRUE
J 0
(-2250 3100);
DISPLAY 0.872340 (-2250 3100);
DISPLAY INVISIBLE (-2250 3100);
FORCEPROP 1 LAST COMMENT_BODY TRUE
J 0
(-2450 3125);
DISPLAY 1.170213 (-2450 3125);
PAINT GREEN (-2450 3125);
DISPLAY INVISIBLE (-2450 3125);
FORCEPROP 2 LAST PATH I38
J 0
(-2825 3275);
DISPLAY 1.021277 (-2825 3275);
DISPLAY INVISIBLE (-2825 3275);
FORCEADD OFFPAGE..5
(-2575 2875);
FORCEPROP 2 LAST $XR1 256 
J 0
(-2950 2875);
DISPLAY 0.638298 (-2950 2875);
PAINT MONO (-2950 2875);
FORCEPROP 2 LAST $XR0 129 
J 0
(-2830 2875);
DISPLAY 0.638298 (-2830 2875);
PAINT MONO (-2830 2875);
FORCEPROP 2 LAST CDS_LIB standard
J 0
(-2575 2875);
DISPLAY INVISIBLE (-2575 2875);
FORCEPROP 1 LAST OFFPAGE TRUE
J 0
(-2250 2750);
DISPLAY 0.872340 (-2250 2750);
DISPLAY INVISIBLE (-2250 2750);
FORCEPROP 1 LAST COMMENT_BODY TRUE
J 0
(-2475 2800);
DISPLAY 1.170213 (-2475 2800);
PAINT GREEN (-2475 2800);
DISPLAY INVISIBLE (-2475 2800);
FORCEPROP 2 LAST PATH I39
J 0
(-2825 2925);
DISPLAY 1.021277 (-2825 2925);
DISPLAY INVISIBLE (-2825 2925);
FORCEADD Q_RES..2
(4175 3350);
FORCEPROP 1 LAST PART_NUMBER CS21002FB06
J 0
(4215 3225);
DISPLAY 0.510638 (4215 3225);
DISPLAY INVISIBLE (4215 3225);
FORCEPROP 1 LAST VALUE 1K
J 0
(4220 3425);
DISPLAY 0.510638 (4220 3425);
FORCEPROP 1 LAST TOLERANCE 1%
J 0
(4220 3375);
DISPLAY 0.510638 (4220 3375);
FORCEPROP 1 LAST PACK_TYPE 0402LF
J 0
(4215 3175);
DISPLAY 0.510638 (4215 3175);
FORCEPROP 1 LAST MATERIAL CHIP
J 0
(4215 3275);
DISPLAY 0.510638 (4215 3275);
FORCEPROP 1 LAST WATTAGE 1/16W
J 0
(4215 3325);
DISPLAY 0.510638 (4215 3325);
FORCEPROP 1 LAST $LOCATION R1823
J 0
(4220 3475);
DISPLAY 0.978723 (4220 3475);
FORCEPROP 1 LASTPIN (4175 3450) $PN 1
J 0
(4180 3412);
DISPLAY 0.787234 (4180 3412);
FORCEPROP 1 LASTPIN (4175 3250) $PN 2
J 0
(4180 3260);
DISPLAY 0.787234 (4180 3260);
FORCEPROP 2 LAST CDS_LIB pure_quanta
J 0
(4175 3350);
PAINT MONO (4175 3350);
DISPLAY INVISIBLE (4175 3350);
FORCEPROP 1 LAST PATH I4
J 0
(4225 3525);
DISPLAY 0.978723 (4225 3525);
PAINT WHITE (4225 3525);
DISPLAY INVISIBLE (4225 3525);
FORCEPROP 2 LAST CDS_LOCATION R1823
J 0
(4225 3575);
DISPLAY 1.021277 (4225 3575);
DISPLAY INVISIBLE (4225 3575);
FORCEPROP 2 LAST $SEC 1
J 0
(4225 3575);
DISPLAY 0.680851 (4225 3575);
PAINT MONO (4225 3575);
DISPLAY INVISIBLE (4225 3575);
FORCEPROP 2 LAST CDS_SEC 1
J 0
(4225 3575);
DISPLAY 1.021277 (4225 3575);
DISPLAY INVISIBLE (4225 3575);
FORCEADD OFFPAGE..2
R 2
(-2575 2925);
FORCEPROP 2 LAST $XR1 256 
J 0
(-2950 2925);
DISPLAY 0.638298 (-2950 2925);
PAINT MONO (-2950 2925);
FORCEPROP 2 LAST $XR0 129 
J 0
(-2830 2925);
DISPLAY 0.638298 (-2830 2925);
PAINT MONO (-2830 2925);
FORCEPROP 2 LAST CDS_LIB standard
J 2
(-2575 2925);
DISPLAY INVISIBLE (-2575 2925);
FORCEPROP 1 LAST OFFPAGE TRUE
J 2
(-2900 2800);
DISPLAY 1.170213 (-2900 2800);
PAINT GREEN (-2900 2800);
DISPLAY INVISIBLE (-2900 2800);
FORCEPROP 1 LAST COMMENT_BODY TRUE
J 2
(-2530 2830);
DISPLAY 1.170213 (-2530 2830);
PAINT GREEN (-2530 2830);
DISPLAY INVISIBLE (-2530 2830);
FORCEPROP 2 LAST PATH I40
J 0
(-2825 2975);
DISPLAY 1.021277 (-2825 2975);
DISPLAY INVISIBLE (-2825 2975);
FORCEADD OFFPAGE..2
R 2
(-2575 2975);
FORCEPROP 2 LAST $XR1 256 
J 0
(-2950 2975);
DISPLAY 0.638298 (-2950 2975);
PAINT MONO (-2950 2975);
FORCEPROP 2 LAST $XR0 129 
J 0
(-2830 2975);
DISPLAY 0.638298 (-2830 2975);
PAINT MONO (-2830 2975);
FORCEPROP 1 LAST OFFPAGE TRUE
J 2
(-2900 2850);
DISPLAY 1.170213 (-2900 2850);
PAINT GREEN (-2900 2850);
DISPLAY INVISIBLE (-2900 2850);
FORCEPROP 1 LAST COMMENT_BODY TRUE
J 2
(-2530 2880);
DISPLAY 1.170213 (-2530 2880);
PAINT GREEN (-2530 2880);
DISPLAY INVISIBLE (-2530 2880);
FORCEPROP 2 LAST CDS_LIB standard
J 2
(-2575 2975);
DISPLAY INVISIBLE (-2575 2975);
FORCEPROP 2 LAST PATH I41
J 0
(-2825 3025);
DISPLAY 1.021277 (-2825 3025);
DISPLAY INVISIBLE (-2825 3025);
FORCEADD OFFPAGE..2
R 2
(-2575 3025);
FORCEPROP 2 LAST $XR1 256 
J 0
(-2950 3025);
DISPLAY 0.638298 (-2950 3025);
PAINT MONO (-2950 3025);
FORCEPROP 2 LAST $XR0 129 
J 0
(-2830 3025);
DISPLAY 0.638298 (-2830 3025);
PAINT MONO (-2830 3025);
FORCEPROP 1 LAST OFFPAGE TRUE
J 2
(-2900 2900);
DISPLAY 1.170213 (-2900 2900);
PAINT GREEN (-2900 2900);
DISPLAY INVISIBLE (-2900 2900);
FORCEPROP 1 LAST COMMENT_BODY TRUE
J 2
(-2530 2930);
DISPLAY 1.170213 (-2530 2930);
PAINT GREEN (-2530 2930);
DISPLAY INVISIBLE (-2530 2930);
FORCEPROP 2 LAST CDS_LIB standard
J 0
(-2575 3025);
DISPLAY INVISIBLE (-2575 3025);
FORCEPROP 2 LAST PATH I42
J 0
(-2825 3075);
DISPLAY 1.021277 (-2825 3075);
DISPLAY INVISIBLE (-2825 3075);
FORCEADD OFFPAGE..5
(-2575 2675);
FORCEPROP 2 LAST $XR1 256 
J 0
(-2950 2675);
DISPLAY 0.638298 (-2950 2675);
PAINT MONO (-2950 2675);
FORCEPROP 2 LAST $XR0 130 
J 0
(-2830 2675);
DISPLAY 0.638298 (-2830 2675);
PAINT MONO (-2830 2675);
FORCEPROP 2 LAST CDS_LIB standard
J 0
(-2575 2675);
DISPLAY INVISIBLE (-2575 2675);
FORCEPROP 2 LAST PATH I43
J 0
(-2825 2725);
DISPLAY 1.021277 (-2825 2725);
DISPLAY INVISIBLE (-2825 2725);
FORCEPROP 1 LAST COMMENT_BODY TRUE
J 0
(-2475 2600);
DISPLAY 1.170213 (-2475 2600);
PAINT GREEN (-2475 2600);
DISPLAY INVISIBLE (-2475 2600);
FORCEPROP 1 LAST OFFPAGE TRUE
J 0
(-2250 2550);
DISPLAY 0.872340 (-2250 2550);
DISPLAY INVISIBLE (-2250 2550);
FORCEADD OFFPAGE..2
R 2
(-2575 2775);
FORCEPROP 2 LAST $XR1 256 
J 0
(-2950 2775);
DISPLAY 0.638298 (-2950 2775);
PAINT MONO (-2950 2775);
FORCEPROP 2 LAST $XR0 130 
J 0
(-2830 2775);
DISPLAY 0.638298 (-2830 2775);
PAINT MONO (-2830 2775);
FORCEPROP 1 LAST OFFPAGE TRUE
J 2
(-2900 2650);
DISPLAY 1.170213 (-2900 2650);
PAINT GREEN (-2900 2650);
DISPLAY INVISIBLE (-2900 2650);
FORCEPROP 1 LAST COMMENT_BODY TRUE
J 2
(-2530 2680);
DISPLAY 1.170213 (-2530 2680);
PAINT GREEN (-2530 2680);
DISPLAY INVISIBLE (-2530 2680);
FORCEPROP 2 LAST CDS_LIB standard
J 2
(-2575 2775);
DISPLAY INVISIBLE (-2575 2775);
FORCEPROP 2 LAST PATH I44
J 0
(-2825 2825);
DISPLAY 1.021277 (-2825 2825);
DISPLAY INVISIBLE (-2825 2825);
FORCEADD OFFPAGE..5
(-2575 2725);
FORCEPROP 2 LAST $XR1 256 
J 0
(-2950 2725);
DISPLAY 0.638298 (-2950 2725);
PAINT MONO (-2950 2725);
FORCEPROP 2 LAST $XR0 130 
J 0
(-2830 2725);
DISPLAY 0.638298 (-2830 2725);
PAINT MONO (-2830 2725);
FORCEPROP 1 LAST OFFPAGE TRUE
J 0
(-2250 2600);
DISPLAY 0.872340 (-2250 2600);
DISPLAY INVISIBLE (-2250 2600);
FORCEPROP 1 LAST COMMENT_BODY TRUE
J 0
(-2475 2650);
DISPLAY 1.170213 (-2475 2650);
PAINT GREEN (-2475 2650);
DISPLAY INVISIBLE (-2475 2650);
FORCEPROP 2 LAST CDS_LIB standard
J 0
(-2575 2725);
DISPLAY INVISIBLE (-2575 2725);
FORCEPROP 2 LAST PATH I45
J 0
(-2825 2775);
DISPLAY 1.021277 (-2825 2775);
DISPLAY INVISIBLE (-2825 2775);
FORCEADD OFFPAGE..5
(-2575 2825);
FORCEPROP 2 LAST $XR1 256 
J 0
(-2950 2825);
DISPLAY 0.638298 (-2950 2825);
PAINT MONO (-2950 2825);
FORCEPROP 2 LAST $XR0 130 
J 0
(-2830 2825);
DISPLAY 0.638298 (-2830 2825);
PAINT MONO (-2830 2825);
FORCEPROP 2 LAST CDS_LIB standard
J 0
(-2575 2825);
DISPLAY INVISIBLE (-2575 2825);
FORCEPROP 1 LAST COMMENT_BODY TRUE
J 0
(-2475 2750);
DISPLAY 1.170213 (-2475 2750);
PAINT GREEN (-2475 2750);
DISPLAY INVISIBLE (-2475 2750);
FORCEPROP 1 LAST OFFPAGE TRUE
J 0
(-2250 2700);
DISPLAY 0.872340 (-2250 2700);
DISPLAY INVISIBLE (-2250 2700);
FORCEPROP 2 LAST PATH I46
J 0
(-2825 2875);
DISPLAY 1.021277 (-2825 2875);
DISPLAY INVISIBLE (-2825 2875);
FORCEADD OFFPAGE..1
(-2575 3175);
FORCEPROP 2 LAST $XR0 225 
J 0
(-2857 3175);
DISPLAY 0.638298 (-2857 3175);
PAINT MONO (-2857 3175);
FORCEPROP 1 LAST COMMENT_BODY TRUE
J 0
(-2450 3075);
DISPLAY 1.170213 (-2450 3075);
PAINT GREEN (-2450 3075);
DISPLAY INVISIBLE (-2450 3075);
FORCEPROP 1 LAST OFFPAGE TRUE
J 0
(-2250 3050);
DISPLAY 1.170213 (-2250 3050);
PAINT GREEN (-2250 3050);
DISPLAY INVISIBLE (-2250 3050);
FORCEPROP 2 LAST CDS_LIB standard
J 2
(-2575 3175);
PAINT MONO (-2575 3175);
DISPLAY INVISIBLE (-2575 3175);
FORCEPROP 2 LAST PATH I47
J 0
(-2825 3225);
DISPLAY 1.021277 (-2825 3225);
DISPLAY INVISIBLE (-2825 3225);
FORCEADD OFFPAGE..1
(-2575 3125);
FORCEPROP 2 LAST $XR0 225 
J 0
(-2857 3125);
DISPLAY 0.638298 (-2857 3125);
PAINT MONO (-2857 3125);
FORCEPROP 1 LAST COMMENT_BODY TRUE
J 0
(-2450 3025);
DISPLAY 1.170213 (-2450 3025);
PAINT GREEN (-2450 3025);
DISPLAY INVISIBLE (-2450 3025);
FORCEPROP 1 LAST OFFPAGE TRUE
J 0
(-2250 3000);
DISPLAY 1.170213 (-2250 3000);
PAINT GREEN (-2250 3000);
DISPLAY INVISIBLE (-2250 3000);
FORCEPROP 2 LAST CDS_LIB standard
J 2
(-2575 3125);
PAINT MONO (-2575 3125);
DISPLAY INVISIBLE (-2575 3125);
FORCEPROP 2 LAST PATH I48
J 0
(-2825 3175);
DISPLAY 1.021277 (-2825 3175);
DISPLAY INVISIBLE (-2825 3175);
FORCEADD OFFPAGE..1
(-2575 3075);
FORCEPROP 2 LAST $XR0 225 
J 0
(-2857 3075);
DISPLAY 0.638298 (-2857 3075);
PAINT MONO (-2857 3075);
FORCEPROP 2 LAST CDS_LIB standard
J 2
(-2575 3075);
PAINT MONO (-2575 3075);
DISPLAY INVISIBLE (-2575 3075);
FORCEPROP 1 LAST OFFPAGE TRUE
J 0
(-2250 2950);
DISPLAY 1.170213 (-2250 2950);
PAINT GREEN (-2250 2950);
DISPLAY INVISIBLE (-2250 2950);
FORCEPROP 1 LAST COMMENT_BODY TRUE
J 0
(-2450 2975);
DISPLAY 1.170213 (-2450 2975);
PAINT GREEN (-2450 2975);
DISPLAY INVISIBLE (-2450 2975);
FORCEPROP 2 LAST PATH I49
J 0
(-2825 3125);
DISPLAY 1.021277 (-2825 3125);
DISPLAY INVISIBLE (-2825 3125);
FORCEADD OFFPAGE..5
(3075 3125);
FORCEPROP 2 LAST $XR1 215 
J 0
(2700 3125);
DISPLAY 0.638298 (2700 3125);
PAINT MONO (2700 3125);
FORCEPROP 2 LAST $XR0 223 
J 0
(2820 3125);
DISPLAY 0.638298 (2820 3125);
PAINT MONO (2820 3125);
FORCEPROP 2 LAST CDS_LIB standard
J 0
(3075 3125);
PAINT MONO (3075 3125);
DISPLAY INVISIBLE (3075 3125);
FORCEPROP 1 LAST OFFPAGE TRUE
J 0
(3400 3000);
DISPLAY 0.872340 (3400 3000);
DISPLAY INVISIBLE (3400 3000);
FORCEPROP 1 LAST COMMENT_BODY TRUE
J 0
(3175 3050);
DISPLAY 1.170213 (3175 3050);
PAINT GREEN (3175 3050);
DISPLAY INVISIBLE (3175 3050);
FORCEPROP 2 LAST PATH I5
J 0
(2825 3175);
DISPLAY 1.021277 (2825 3175);
DISPLAY INVISIBLE (2825 3175);
FORCEADD OFFPAGE..1
(-2600 2275);
FORCEPROP 2 LAST $XR0 225 
J 0
(-2852 2275);
DISPLAY 0.638298 (-2852 2275);
PAINT MONO (-2852 2275);
FORCEPROP 2 LAST CDS_LIB standard
J 0
(-2600 2275);
DISPLAY INVISIBLE (-2600 2275);
FORCEPROP 1 LAST COMMENT_BODY TRUE
J 0
(-2475 2175);
DISPLAY 1.170213 (-2475 2175);
PAINT GREEN (-2475 2175);
DISPLAY INVISIBLE (-2475 2175);
FORCEPROP 1 LAST OFFPAGE TRUE
J 0
(-2275 2150);
DISPLAY 0.872340 (-2275 2150);
DISPLAY INVISIBLE (-2275 2150);
FORCEPROP 2 LAST PATH I50
J 0
(-2875 2325);
DISPLAY 1.021277 (-2875 2325);
DISPLAY INVISIBLE (-2875 2325);
FORCEADD OFFPAGE..1
(-2600 2325);
FORCEPROP 2 LAST $XR0 225 
J 0
(-2852 2325);
DISPLAY 0.638298 (-2852 2325);
PAINT MONO (-2852 2325);
FORCEPROP 2 LAST CDS_LIB standard
J 0
(-2600 2325);
DISPLAY INVISIBLE (-2600 2325);
FORCEPROP 1 LAST OFFPAGE TRUE
J 0
(-2275 2200);
DISPLAY 0.872340 (-2275 2200);
DISPLAY INVISIBLE (-2275 2200);
FORCEPROP 1 LAST COMMENT_BODY TRUE
J 0
(-2475 2225);
DISPLAY 1.170213 (-2475 2225);
PAINT GREEN (-2475 2225);
DISPLAY INVISIBLE (-2475 2225);
FORCEPROP 2 LAST PATH I51
J 0
(-2875 2375);
DISPLAY 1.021277 (-2875 2375);
DISPLAY INVISIBLE (-2875 2375);
FORCEADD OFFPAGE..1
(-2600 2375);
FORCEPROP 2 LAST $XR0 225 
J 0
(-2852 2375);
DISPLAY 0.638298 (-2852 2375);
PAINT MONO (-2852 2375);
FORCEPROP 1 LAST COMMENT_BODY TRUE
J 0
(-2475 2275);
DISPLAY 1.170213 (-2475 2275);
PAINT GREEN (-2475 2275);
DISPLAY INVISIBLE (-2475 2275);
FORCEPROP 1 LAST OFFPAGE TRUE
J 0
(-2275 2250);
DISPLAY 1.170213 (-2275 2250);
PAINT GREEN (-2275 2250);
DISPLAY INVISIBLE (-2275 2250);
FORCEPROP 2 LAST CDS_LIB standard
J 2
(-2600 2375);
PAINT MONO (-2600 2375);
DISPLAY INVISIBLE (-2600 2375);
FORCEPROP 2 LAST PATH I52
J 0
(-2875 2425);
DISPLAY 1.021277 (-2875 2425);
DISPLAY INVISIBLE (-2875 2425);
FORCEADD OFFPAGE..1
(-2600 2175);
FORCEPROP 2 LAST $XR0 122 
J 0
(-2852 2175);
DISPLAY 0.638298 (-2852 2175);
PAINT MONO (-2852 2175);
FORCEPROP 1 LAST OFFPAGE TRUE
J 0
(-2275 2050);
DISPLAY 0.872340 (-2275 2050);
DISPLAY INVISIBLE (-2275 2050);
FORCEPROP 1 LAST COMMENT_BODY TRUE
J 0
(-2475 2075);
DISPLAY 1.170213 (-2475 2075);
PAINT GREEN (-2475 2075);
DISPLAY INVISIBLE (-2475 2075);
FORCEPROP 2 LAST CDS_LIB standard
J 0
(-2600 2175);
DISPLAY INVISIBLE (-2600 2175);
FORCEPROP 2 LAST PATH I55
J 0
(-2875 2225);
DISPLAY 1.021277 (-2875 2225);
DISPLAY INVISIBLE (-2875 2225);
FORCEADD OFFPAGE..1
(-2600 2225);
FORCEPROP 2 LAST $XR0 122 
J 0
(-2852 2225);
DISPLAY 0.638298 (-2852 2225);
PAINT MONO (-2852 2225);
FORCEPROP 2 LAST CDS_LIB standard
J 2
(-2600 2225);
PAINT MONO (-2600 2225);
DISPLAY INVISIBLE (-2600 2225);
FORCEPROP 1 LAST COMMENT_BODY TRUE
J 0
(-2475 2125);
DISPLAY 1.170213 (-2475 2125);
PAINT GREEN (-2475 2125);
DISPLAY INVISIBLE (-2475 2125);
FORCEPROP 1 LAST OFFPAGE TRUE
J 0
(-2275 2100);
DISPLAY 1.170213 (-2275 2100);
PAINT GREEN (-2275 2100);
DISPLAY INVISIBLE (-2275 2100);
FORCEPROP 2 LAST PATH I56
J 0
(-2875 2275);
DISPLAY 1.021277 (-2875 2275);
DISPLAY INVISIBLE (-2875 2275);
FORCEADD OFFPAGE..1
(-2600 1975);
FORCEPROP 2 LAST $XR0 121 
J 0
(-2852 1975);
DISPLAY 0.638298 (-2852 1975);
PAINT MONO (-2852 1975);
FORCEPROP 1 LAST COMMENT_BODY TRUE
J 0
(-2475 1875);
DISPLAY 1.170213 (-2475 1875);
PAINT GREEN (-2475 1875);
DISPLAY INVISIBLE (-2475 1875);
FORCEPROP 1 LAST OFFPAGE TRUE
J 0
(-2275 1850);
DISPLAY 1.170213 (-2275 1850);
PAINT GREEN (-2275 1850);
DISPLAY INVISIBLE (-2275 1850);
FORCEPROP 2 LAST PATH I57
J 0
(-2875 2025);
DISPLAY 1.021277 (-2875 2025);
DISPLAY INVISIBLE (-2875 2025);
FORCEPROP 2 LAST CDS_LIB standard
J 2
(-2600 1975);
PAINT MONO (-2600 1975);
DISPLAY INVISIBLE (-2600 1975);
FORCEADD OFFPAGE..1
(-2600 2025);
FORCEPROP 2 LAST $XR0 121 
J 0
(-2852 2025);
DISPLAY 0.638298 (-2852 2025);
PAINT MONO (-2852 2025);
FORCEPROP 2 LAST CDS_LIB standard
J 2
(-2600 2025);
PAINT MONO (-2600 2025);
DISPLAY INVISIBLE (-2600 2025);
FORCEPROP 1 LAST OFFPAGE TRUE
J 0
(-2275 1900);
DISPLAY 1.170213 (-2275 1900);
PAINT GREEN (-2275 1900);
DISPLAY INVISIBLE (-2275 1900);
FORCEPROP 1 LAST COMMENT_BODY TRUE
J 0
(-2475 1925);
DISPLAY 1.170213 (-2475 1925);
PAINT GREEN (-2475 1925);
DISPLAY INVISIBLE (-2475 1925);
FORCEPROP 2 LAST PATH I58
J 0
(-2875 2075);
DISPLAY 1.021277 (-2875 2075);
DISPLAY INVISIBLE (-2875 2075);
FORCEADD OFFPAGE..1
(-2600 2075);
FORCEPROP 2 LAST $XR0 123 
J 0
(-2852 2075);
DISPLAY 0.638298 (-2852 2075);
PAINT MONO (-2852 2075);
FORCEPROP 1 LAST COMMENT_BODY TRUE
J 0
(-2475 1975);
DISPLAY 1.170213 (-2475 1975);
PAINT GREEN (-2475 1975);
DISPLAY INVISIBLE (-2475 1975);
FORCEPROP 1 LAST OFFPAGE TRUE
J 0
(-2275 1950);
DISPLAY 0.872340 (-2275 1950);
DISPLAY INVISIBLE (-2275 1950);
FORCEPROP 2 LAST CDS_LIB standard
J 0
(-2600 2075);
DISPLAY INVISIBLE (-2600 2075);
FORCEPROP 2 LAST PATH I59
J 0
(-2875 2125);
DISPLAY 1.021277 (-2875 2125);
DISPLAY INVISIBLE (-2875 2125);
FORCEADD OFFPAGE..1
(-2600 2125);
FORCEPROP 2 LAST $XR0 123 
J 0
(-2852 2125);
DISPLAY 0.638298 (-2852 2125);
PAINT MONO (-2852 2125);
FORCEPROP 1 LAST OFFPAGE TRUE
J 0
(-2275 2000);
DISPLAY 0.872340 (-2275 2000);
DISPLAY INVISIBLE (-2275 2000);
FORCEPROP 1 LAST COMMENT_BODY TRUE
J 0
(-2475 2025);
DISPLAY 1.170213 (-2475 2025);
PAINT GREEN (-2475 2025);
DISPLAY INVISIBLE (-2475 2025);
FORCEPROP 2 LAST CDS_LIB standard
J 0
(-2600 2125);
DISPLAY INVISIBLE (-2600 2125);
FORCEPROP 2 LAST PATH I60
J 0
(-2875 2175);
DISPLAY 1.021277 (-2875 2175);
DISPLAY INVISIBLE (-2875 2175);
FORCEADD OFFPAGE..1
(-2600 1725);
FORCEPROP 2 LAST $XR1 255 
J 0
(-2972 1725);
DISPLAY 0.638298 (-2972 1725);
PAINT MONO (-2972 1725);
FORCEPROP 2 LAST $XR0 226 
J 0
(-2852 1725);
DISPLAY 0.638298 (-2852 1725);
PAINT MONO (-2852 1725);
FORCEPROP 2 LAST CDS_LIB standard
J 0
(-2600 1725);
DISPLAY INVISIBLE (-2600 1725);
FORCEPROP 1 LAST COMMENT_BODY TRUE
J 0
(-2475 1625);
DISPLAY 1.170213 (-2475 1625);
PAINT GREEN (-2475 1625);
DISPLAY INVISIBLE (-2475 1625);
FORCEPROP 1 LAST OFFPAGE TRUE
J 0
(-2275 1600);
DISPLAY 0.872340 (-2275 1600);
DISPLAY INVISIBLE (-2275 1600);
FORCEPROP 2 LAST PATH I62
J 0
(-2875 1775);
DISPLAY 1.021277 (-2875 1775);
DISPLAY INVISIBLE (-2875 1775);
FORCEADD OFFPAGE..1
R 2
(875 -125);
FORCEPROP 2 LAST $XR0 221 
J 0
(1061 -125);
DISPLAY 0.638298 (1061 -125);
PAINT MONO (1061 -125);
FORCEPROP 2 LAST PATH I68
J 0
(1250 -75);
DISPLAY 1.021277 (1250 -75);
DISPLAY INVISIBLE (1250 -75);
FORCEPROP 2 LAST CDS_LIB standard
J 2
(875 -125);
PAINT MONO (875 -125);
DISPLAY INVISIBLE (875 -125);
FORCEPROP 1 LAST OFFPAGE TRUE
J 2
(550 -250);
DISPLAY 0.872340 (550 -250);
DISPLAY INVISIBLE (550 -250);
FORCEPROP 1 LAST COMMENT_BODY TRUE
J 2
(750 -225);
DISPLAY 1.170213 (750 -225);
PAINT GREEN (750 -225);
DISPLAY INVISIBLE (750 -225);
FORCEADD OFFPAGE..1
R 2
(875 -175);
FORCEPROP 2 LAST $XR0 221 
J 0
(1061 -175);
DISPLAY 0.638298 (1061 -175);
PAINT MONO (1061 -175);
FORCEPROP 2 LAST PATH I69
J 0
(1075 -125);
DISPLAY 1.021277 (1075 -125);
DISPLAY INVISIBLE (1075 -125);
FORCEPROP 1 LAST COMMENT_BODY TRUE
J 2
(750 -275);
DISPLAY 1.170213 (750 -275);
PAINT GREEN (750 -275);
DISPLAY INVISIBLE (750 -275);
FORCEPROP 1 LAST OFFPAGE TRUE
J 2
(550 -300);
DISPLAY 0.872340 (550 -300);
DISPLAY INVISIBLE (550 -300);
FORCEPROP 2 LAST CDS_LIB standard
J 2
(875 -175);
PAINT MONO (875 -175);
DISPLAY INVISIBLE (875 -175);
FORCEADD OFFPAGE..2
(950 3425);
FORCEPROP 2 LAST $XR1 219 
J 0
(1259 3425);
DISPLAY 0.638298 (1259 3425);
PAINT MONO (1259 3425);
FORCEPROP 2 LAST $XR0 124 
J 0
(1139 3425);
DISPLAY 0.638298 (1139 3425);
PAINT MONO (1139 3425);
FORCEPROP 2 LAST PATH I7
J 0
(1275 3475);
DISPLAY 1.021277 (1275 3475);
DISPLAY INVISIBLE (1275 3475);
FORCEPROP 2 LAST CDS_LIB standard
J 0
(950 3425);
DISPLAY INVISIBLE (950 3425);
FORCEPROP 1 LAST COMMENT_BODY TRUE
J 0
(905 3330);
DISPLAY 1.170213 (905 3330);
PAINT GREEN (905 3330);
DISPLAY INVISIBLE (905 3330);
FORCEPROP 1 LAST OFFPAGE TRUE
J 0
(1275 3300);
DISPLAY 1.170213 (1275 3300);
PAINT GREEN (1275 3300);
DISPLAY INVISIBLE (1275 3300);
FORCEADD LCMXO3LF9400C5BG484C..4
(-925 -175);
FORCEPROP 1 LAST PART_NUMBER AJ094000T08
J 0
(-1322 213);
DISPLAY 0.723404 (-1322 213);
PAINT GREEN (-1322 213);
DISPLAY INVISIBLE (-1322 213);
FORCEPROP 1 LAST MATERIAL IC
J 0
(-1322 86);
DISPLAY 0.723404 (-1322 86);
PAINT GREEN (-1322 86);
FORCEPROP 2 LAST PART_TYPE SMLF
J 0
(-1300 450);
DISPLAY 1.021277 (-1300 450);
FORCEPROP 2 LAST VALUE LCMXO3LF-9400C-5BG484C
J 0
(-1300 400);
DISPLAY 1.021277 (-1300 400);
FORCEPROP 1 LAST $LOCATION U249
J 0
(-1322 360);
DISPLAY 0.723404 (-1322 360);
PAINT GREEN (-1322 360);
FORCEPROP 0 LASTPIN (-375 25) $PN E8
J 0
(-365 35);
DISPLAY 0.680851 (-365 35);
PAINT MONO (-365 35);
FORCEPROP 0 LASTPIN (-375 -25) $PN E9
J 0
(-365 -15);
DISPLAY 0.680851 (-365 -15);
PAINT MONO (-365 -15);
FORCEPROP 0 LASTPIN (-375 -75) $PN D10
J 0
(-365 -65);
DISPLAY 0.680851 (-365 -65);
PAINT MONO (-365 -65);
FORCEPROP 0 LASTPIN (-375 -125) $PN C10
J 0
(-365 -115);
DISPLAY 0.680851 (-365 -115);
PAINT MONO (-365 -115);
FORCEPROP 0 LASTPIN (-375 -175) $PN E14
J 0
(-365 -165);
DISPLAY 0.680851 (-365 -165);
PAINT MONO (-365 -165);
FORCEPROP 0 LASTPIN (-375 -225) $PN E15
J 0
(-365 -215);
DISPLAY 0.680851 (-365 -215);
PAINT MONO (-365 -215);
FORCEPROP 0 LASTPIN (-375 -275) $PN F16
J 0
(-365 -265);
DISPLAY 0.680851 (-365 -265);
PAINT MONO (-365 -265);
FORCEPROP 0 LASTPIN (-375 -325) $PN E17
J 0
(-365 -315);
DISPLAY 0.680851 (-365 -315);
PAINT MONO (-365 -315);
FORCEPROP 1 LAST PATH I70
J 0
(-925 -175);
DISPLAY 0.723404 (-925 -175);
PAINT GREEN (-925 -175);
DISPLAY INVISIBLE (-925 -175);
FORCEPROP 1 LAST CDS_LMAN_SYM_OUTLINE -400,250,400,-250
J 0
(-925 -175);
DISPLAY 0.468085 (-925 -175);
PAINT GREEN (-925 -175);
DISPLAY INVISIBLE (-925 -175);
FORCEPROP 1 LAST NEEDS_NO_SIZE TRUE
J 0
(-925 -175);
DISPLAY 0.723404 (-925 -175);
PAINT GREEN (-925 -175);
DISPLAY INVISIBLE (-925 -175);
FORCEPROP 2 LAST CDS_LIB pure_quanta
J 0
(-925 -175);
DISPLAY INVISIBLE (-925 -175);
FORCEPROP 0 LAST CDS_LOCATION U249
J 0
(-1300 500);
DISPLAY 1.021277 (-1300 500);
DISPLAY INVISIBLE (-1300 500);
FORCEPROP 0 LAST $SEC 4
J 0
(-1300 500);
DISPLAY 0.680851 (-1300 500);
PAINT MONO (-1300 500);
DISPLAY INVISIBLE (-1300 500);
FORCEPROP 0 LAST CDS_SEC 4
J 0
(-1300 500);
DISPLAY 1.021277 (-1300 500);
DISPLAY INVISIBLE (-1300 500);
FORCEADD OFFPAGE..1
R 2
(950 3025);
FORCEPROP 2 LAST $XR0 195 
J 0
(1136 3025);
DISPLAY 0.638298 (1136 3025);
PAINT MONO (1136 3025);
FORCEPROP 2 LAST CDS_LIB standard
J 0
(950 3025);
DISPLAY INVISIBLE (950 3025);
FORCEPROP 2 LAST PATH I71
J 0
(1125 3100);
DISPLAY 1.021277 (1125 3100);
DISPLAY INVISIBLE (1125 3100);
FORCEPROP 1 LAST COMMENT_BODY TRUE
J 2
(825 2925);
DISPLAY 1.170213 (825 2925);
PAINT GREEN (825 2925);
DISPLAY INVISIBLE (825 2925);
FORCEPROP 1 LAST OFFPAGE TRUE
J 2
(625 2900);
DISPLAY 1.170213 (625 2900);
PAINT GREEN (625 2900);
DISPLAY INVISIBLE (625 2900);
FORCEADD OFFPAGE..1
R 2
(950 2975);
FORCEPROP 2 LAST $XR0 195 
J 0
(1136 2975);
DISPLAY 0.638298 (1136 2975);
PAINT MONO (1136 2975);
FORCEPROP 2 LAST CDS_LIB standard
J 0
(950 2975);
DISPLAY INVISIBLE (950 2975);
FORCEPROP 2 LAST PATH I72
J 0
(1125 3050);
DISPLAY 1.021277 (1125 3050);
DISPLAY INVISIBLE (1125 3050);
FORCEPROP 1 LAST OFFPAGE TRUE
J 2
(625 2850);
DISPLAY 1.170213 (625 2850);
PAINT GREEN (625 2850);
DISPLAY INVISIBLE (625 2850);
FORCEPROP 1 LAST COMMENT_BODY TRUE
J 2
(825 2875);
DISPLAY 1.170213 (825 2875);
PAINT GREEN (825 2875);
DISPLAY INVISIBLE (825 2875);
FORCEADD OFFPAGE..1
R 2
(950 2875);
FORCEPROP 2 LAST $XR0 195 
J 0
(1136 2875);
DISPLAY 0.638298 (1136 2875);
PAINT MONO (1136 2875);
FORCEPROP 1 LAST COMMENT_BODY TRUE
J 2
(825 2775);
DISPLAY 1.170213 (825 2775);
PAINT GREEN (825 2775);
DISPLAY INVISIBLE (825 2775);
FORCEPROP 1 LAST OFFPAGE TRUE
J 2
(625 2750);
DISPLAY 1.170213 (625 2750);
PAINT GREEN (625 2750);
DISPLAY INVISIBLE (625 2750);
FORCEPROP 2 LAST PATH I73
J 0
(1125 2950);
DISPLAY 1.021277 (1125 2950);
DISPLAY INVISIBLE (1125 2950);
FORCEPROP 2 LAST CDS_LIB standard
J 0
(950 2875);
DISPLAY INVISIBLE (950 2875);
FORCEADD OFFPAGE..1
R 2
(950 2925);
FORCEPROP 2 LAST $XR0 195 
J 0
(1136 2925);
DISPLAY 0.638298 (1136 2925);
PAINT MONO (1136 2925);
FORCEPROP 1 LAST OFFPAGE TRUE
J 2
(625 2800);
DISPLAY 1.170213 (625 2800);
PAINT GREEN (625 2800);
DISPLAY INVISIBLE (625 2800);
FORCEPROP 1 LAST COMMENT_BODY TRUE
J 2
(825 2825);
DISPLAY 1.170213 (825 2825);
PAINT GREEN (825 2825);
DISPLAY INVISIBLE (825 2825);
FORCEPROP 2 LAST PATH I74
J 0
(1125 3000);
DISPLAY 1.021277 (1125 3000);
DISPLAY INVISIBLE (1125 3000);
FORCEPROP 2 LAST CDS_LIB standard
J 0
(950 2925);
DISPLAY INVISIBLE (950 2925);
FORCEADD OFFPAGE..1
R 2
(950 2825);
FORCEPROP 2 LAST $XR0 195 
J 0
(1136 2825);
DISPLAY 0.638298 (1136 2825);
PAINT MONO (1136 2825);
FORCEPROP 1 LAST COMMENT_BODY TRUE
J 2
(825 2725);
DISPLAY 1.170213 (825 2725);
PAINT GREEN (825 2725);
DISPLAY INVISIBLE (825 2725);
FORCEPROP 1 LAST OFFPAGE TRUE
J 2
(625 2700);
DISPLAY 1.170213 (625 2700);
PAINT GREEN (625 2700);
DISPLAY INVISIBLE (625 2700);
FORCEPROP 2 LAST PATH I75
J 0
(1125 2900);
DISPLAY 1.021277 (1125 2900);
DISPLAY INVISIBLE (1125 2900);
FORCEPROP 2 LAST CDS_LIB standard
J 0
(950 2825);
DISPLAY INVISIBLE (950 2825);
FORCEADD OFFPAGE..1
R 2
(950 2775);
FORCEPROP 2 LAST $XR0 195 
J 0
(1136 2775);
DISPLAY 0.638298 (1136 2775);
PAINT MONO (1136 2775);
FORCEPROP 1 LAST OFFPAGE TRUE
J 2
(625 2650);
DISPLAY 1.170213 (625 2650);
PAINT GREEN (625 2650);
DISPLAY INVISIBLE (625 2650);
FORCEPROP 1 LAST COMMENT_BODY TRUE
J 2
(825 2675);
DISPLAY 1.170213 (825 2675);
PAINT GREEN (825 2675);
DISPLAY INVISIBLE (825 2675);
FORCEPROP 2 LAST PATH I76
J 0
(1125 2850);
DISPLAY 1.021277 (1125 2850);
DISPLAY INVISIBLE (1125 2850);
FORCEPROP 2 LAST CDS_LIB standard
J 0
(950 2775);
DISPLAY INVISIBLE (950 2775);
FORCEADD OFFPAGE..1
R 2
(950 2725);
FORCEPROP 2 LAST $XR0 195 
J 0
(1136 2725);
DISPLAY 0.638298 (1136 2725);
PAINT MONO (1136 2725);
FORCEPROP 1 LAST COMMENT_BODY TRUE
J 2
(825 2625);
DISPLAY 1.170213 (825 2625);
PAINT GREEN (825 2625);
DISPLAY INVISIBLE (825 2625);
FORCEPROP 1 LAST OFFPAGE TRUE
J 2
(625 2600);
DISPLAY 1.170213 (625 2600);
PAINT GREEN (625 2600);
DISPLAY INVISIBLE (625 2600);
FORCEPROP 2 LAST PATH I77
J 0
(1125 2800);
DISPLAY 1.021277 (1125 2800);
DISPLAY INVISIBLE (1125 2800);
FORCEPROP 2 LAST CDS_LIB standard
J 0
(950 2725);
DISPLAY INVISIBLE (950 2725);
FORCEADD OFFPAGE..1
R 2
(950 2675);
FORCEPROP 2 LAST $XR0 195 
J 0
(1136 2675);
DISPLAY 0.638298 (1136 2675);
PAINT MONO (1136 2675);
FORCEPROP 1 LAST OFFPAGE TRUE
J 2
(625 2550);
DISPLAY 1.170213 (625 2550);
PAINT GREEN (625 2550);
DISPLAY INVISIBLE (625 2550);
FORCEPROP 1 LAST COMMENT_BODY TRUE
J 2
(825 2575);
DISPLAY 1.170213 (825 2575);
PAINT GREEN (825 2575);
DISPLAY INVISIBLE (825 2575);
FORCEPROP 2 LAST PATH I78
J 0
(1125 2750);
DISPLAY 1.021277 (1125 2750);
DISPLAY INVISIBLE (1125 2750);
FORCEPROP 2 LAST CDS_LIB standard
J 0
(950 2675);
DISPLAY INVISIBLE (950 2675);
FORCEADD Q_RES..1
(-975 -1150);
FORCEPROP 1 LAST PART_NUMBER CS03322FB03
J 0
(-1125 -1075);
DISPLAY 0.638298 (-1125 -1075);
DISPLAY INVISIBLE (-1125 -1075);
FORCEPROP 1 LAST TOLERANCE 1%
J 0
(-700 -1150);
DISPLAY 0.638298 (-700 -1150);
FORCEPROP 1 LAST VALUE 33.2
J 2
(-725 -1150);
DISPLAY 0.638298 (-725 -1150);
FORCEPROP 1 LAST MATERIAL CHIP
J 0
(-625 -1150);
DISPLAY 0.638298 (-625 -1150);
FORCEPROP 1 LAST $LOCATION R4751
J 0
(-1250 -1150);
DISPLAY 0.638298 (-1250 -1150);
FORCEPROP 1 LASTPIN (-1075 -1150) $PN 1
J 0
(-1063 -1138);
DISPLAY 0.787234 (-1063 -1138);
PAINT MONO (-1063 -1138);
FORCEPROP 1 LASTPIN (-875 -1150) $PN 2
J 0
(-913 -1138);
DISPLAY 0.787234 (-913 -1138);
PAINT MONO (-913 -1138);
FORCEPROP 1 LAST PATH I79
J 0
(-1025 -1000);
DISPLAY 0.978723 (-1025 -1000);
PAINT WHITE (-1025 -1000);
DISPLAY INVISIBLE (-1025 -1000);
FORCEPROP 1 LAST PACK_TYPE 0402LF
J 0
(-1125 -1025);
DISPLAY 0.638298 (-1125 -1025);
DISPLAY INVISIBLE (-1125 -1025);
FORCEPROP 1 LAST WATTAGE 1/16W
J 2
(-775 -1025);
DISPLAY 0.638298 (-775 -1025);
DISPLAY INVISIBLE (-775 -1025);
FORCEPROP 2 LAST CDS_LIB pure_quanta
J 0
(-975 -1150);
DISPLAY INVISIBLE (-975 -1150);
FORCEPROP 0 LAST CDS_LOCATION R4751
J 0
(-1025 -1050);
DISPLAY 1.021277 (-1025 -1050);
DISPLAY INVISIBLE (-1025 -1050);
FORCEPROP 0 LAST $SEC 1
J 0
(-1025 -1050);
DISPLAY 0.680851 (-1025 -1050);
PAINT MONO (-1025 -1050);
DISPLAY INVISIBLE (-1025 -1050);
FORCEPROP 0 LAST CDS_SEC 1
J 0
(-1025 -1050);
DISPLAY 1.021277 (-1025 -1050);
DISPLAY INVISIBLE (-1025 -1050);
FORCEADD OFFPAGE..2
(950 3375);
FORCEPROP 2 LAST $XR1 219 
J 0
(1259 3375);
DISPLAY 0.638298 (1259 3375);
PAINT MONO (1259 3375);
FORCEPROP 2 LAST $XR0 124 
J 0
(1139 3375);
DISPLAY 0.638298 (1139 3375);
PAINT MONO (1139 3375);
FORCEPROP 2 LAST PATH I8
J 0
(1275 3425);
DISPLAY 1.021277 (1275 3425);
DISPLAY INVISIBLE (1275 3425);
FORCEPROP 1 LAST COMMENT_BODY TRUE
J 0
(905 3280);
DISPLAY 1.170213 (905 3280);
PAINT GREEN (905 3280);
DISPLAY INVISIBLE (905 3280);
FORCEPROP 1 LAST OFFPAGE TRUE
J 0
(1275 3250);
DISPLAY 1.170213 (1275 3250);
PAINT GREEN (1275 3250);
DISPLAY INVISIBLE (1275 3250);
FORCEPROP 2 LAST CDS_LIB standard
J 0
(950 3375);
DISPLAY INVISIBLE (950 3375);
FORCEADD OFFPAGE..1
(-2275 -1150);
FORCEPROP 2 LAST $XR0 158 
J 0
(-2527 -1150);
DISPLAY 0.638298 (-2527 -1150);
PAINT MONO (-2527 -1150);
FORCEPROP 2 LAST PATH I80
J 2
(-2450 -1075);
DISPLAY 1.021277 (-2450 -1075);
DISPLAY INVISIBLE (-2450 -1075);
FORCEPROP 1 LAST OFFPAGE TRUE
J 0
(-1950 -1275);
DISPLAY 0.872340 (-1950 -1275);
DISPLAY INVISIBLE (-1950 -1275);
FORCEPROP 1 LAST COMMENT_BODY TRUE
J 0
(-2150 -1250);
DISPLAY 1.170213 (-2150 -1250);
PAINT GREEN (-2150 -1250);
DISPLAY INVISIBLE (-2150 -1250);
FORCEPROP 2 LAST CDS_LIB standard
J 2
(-2275 -1150);
DISPLAY INVISIBLE (-2275 -1150);
FORCEADD OFFPAGE..5
R 2
(550 -1150);
FORCEPROP 2 LAST $XR0 216 
J 0
(739 -1150);
DISPLAY 0.638298 (739 -1150);
PAINT MONO (739 -1150);
FORCEPROP 2 LAST PATH I81
J 0
(725 -1075);
DISPLAY 1.021277 (725 -1075);
DISPLAY INVISIBLE (725 -1075);
FORCEPROP 2 LAST CDS_LIB standard
J 0
(550 -1150);
DISPLAY INVISIBLE (550 -1150);
FORCEPROP 1 LAST OFFPAGE TRUE
J 2
(225 -1275);
DISPLAY 0.872340 (225 -1275);
DISPLAY INVISIBLE (225 -1275);
FORCEPROP 1 LAST COMMENT_BODY TRUE
J 2
(450 -1225);
DISPLAY 1.170213 (450 -1225);
PAINT GREEN (450 -1225);
DISPLAY INVISIBLE (450 -1225);
FORCEADD OFFPAGE..1
(-2600 1325);
FORCEPROP 2 LAST $XR0 216 
J 0
(-2852 1325);
DISPLAY 0.638298 (-2852 1325);
PAINT MONO (-2852 1325);
FORCEPROP 2 LAST CDS_LIB standard
J 0
(-2600 1325);
DISPLAY INVISIBLE (-2600 1325);
FORCEPROP 2 LAST PATH I82
J 0
(-2550 1400);
DISPLAY 1.021277 (-2550 1400);
DISPLAY INVISIBLE (-2550 1400);
FORCEPROP 1 LAST COMMENT_BODY TRUE
J 0
(-2475 1225);
DISPLAY 1.170213 (-2475 1225);
PAINT GREEN (-2475 1225);
DISPLAY INVISIBLE (-2475 1225);
FORCEPROP 1 LAST OFFPAGE TRUE
J 0
(-2275 1200);
DISPLAY 1.170213 (-2275 1200);
PAINT GREEN (-2275 1200);
DISPLAY INVISIBLE (-2275 1200);
FORCEADD OFFPAGE..1
(-2600 1225);
FORCEPROP 2 LAST $XR0 156 
J 0
(-2852 1225);
DISPLAY 0.638298 (-2852 1225);
PAINT MONO (-2852 1225);
FORCEPROP 2 LAST CDS_LIB standard
J 0
(-2600 1225);
DISPLAY INVISIBLE (-2600 1225);
FORCEPROP 2 LAST PATH I83
J 0
(-2550 1300);
DISPLAY 1.021277 (-2550 1300);
DISPLAY INVISIBLE (-2550 1300);
FORCEPROP 1 LAST COMMENT_BODY TRUE
J 0
(-2475 1125);
DISPLAY 1.170213 (-2475 1125);
PAINT GREEN (-2475 1125);
DISPLAY INVISIBLE (-2475 1125);
FORCEPROP 1 LAST OFFPAGE TRUE
J 0
(-2275 1100);
DISPLAY 1.170213 (-2275 1100);
PAINT GREEN (-2275 1100);
DISPLAY INVISIBLE (-2275 1100);
FORCEADD OFFPAGE..1
(-2600 1175);
FORCEPROP 2 LAST $XR0 162 
J 0
(-2852 1175);
DISPLAY 0.638298 (-2852 1175);
PAINT MONO (-2852 1175);
FORCEPROP 1 LAST COMMENT_BODY TRUE
J 0
(-2475 1075);
DISPLAY 1.170213 (-2475 1075);
PAINT GREEN (-2475 1075);
DISPLAY INVISIBLE (-2475 1075);
FORCEPROP 1 LAST OFFPAGE TRUE
J 0
(-2275 1050);
DISPLAY 1.170213 (-2275 1050);
PAINT GREEN (-2275 1050);
DISPLAY INVISIBLE (-2275 1050);
FORCEPROP 2 LAST PATH I84
J 0
(-2550 1250);
DISPLAY 1.021277 (-2550 1250);
DISPLAY INVISIBLE (-2550 1250);
FORCEPROP 2 LAST CDS_LIB standard
J 0
(-2600 1175);
DISPLAY INVISIBLE (-2600 1175);
FORCEADD OFFPAGE..1
(-2600 1275);
FORCEPROP 2 LAST $XR0 216 
J 0
(-2852 1275);
DISPLAY 0.638298 (-2852 1275);
PAINT MONO (-2852 1275);
FORCEPROP 1 LAST COMMENT_BODY TRUE
J 0
(-2475 1175);
DISPLAY 1.170213 (-2475 1175);
PAINT GREEN (-2475 1175);
DISPLAY INVISIBLE (-2475 1175);
FORCEPROP 1 LAST OFFPAGE TRUE
J 0
(-2275 1150);
DISPLAY 1.170213 (-2275 1150);
PAINT GREEN (-2275 1150);
DISPLAY INVISIBLE (-2275 1150);
FORCEPROP 2 LAST PATH I85
J 0
(-2550 1350);
DISPLAY 1.021277 (-2550 1350);
DISPLAY INVISIBLE (-2550 1350);
FORCEPROP 2 LAST CDS_LIB standard
J 0
(-2600 1275);
DISPLAY INVISIBLE (-2600 1275);
FORCEADD Q_RES..1
(-975 -1300);
FORCEPROP 1 LAST PART_NUMBER CS03322FB03
J 0
(-1125 -1225);
DISPLAY 0.638298 (-1125 -1225);
DISPLAY INVISIBLE (-1125 -1225);
FORCEPROP 1 LAST VALUE 33.2
J 2
(-725 -1300);
DISPLAY 0.638298 (-725 -1300);
FORCEPROP 1 LAST MATERIAL CHIP
J 0
(-625 -1300);
DISPLAY 0.638298 (-625 -1300);
FORCEPROP 1 LAST TOLERANCE 1%
J 0
(-700 -1300);
DISPLAY 0.638298 (-700 -1300);
FORCEPROP 1 LAST $LOCATION R4760
J 0
(-1250 -1300);
DISPLAY 0.638298 (-1250 -1300);
FORCEPROP 1 LASTPIN (-1075 -1300) $PN 1
J 0
(-1063 -1288);
DISPLAY 0.787234 (-1063 -1288);
PAINT MONO (-1063 -1288);
FORCEPROP 1 LASTPIN (-875 -1300) $PN 2
J 0
(-913 -1288);
DISPLAY 0.787234 (-913 -1288);
PAINT MONO (-913 -1288);
FORCEPROP 1 LAST PACK_TYPE 0402LF
J 0
(-1125 -1175);
DISPLAY 0.638298 (-1125 -1175);
DISPLAY INVISIBLE (-1125 -1175);
FORCEPROP 1 LAST WATTAGE 1/16W
J 2
(-775 -1175);
DISPLAY 0.638298 (-775 -1175);
DISPLAY INVISIBLE (-775 -1175);
FORCEPROP 2 LAST CDS_LIB pure_quanta
J 0
(-975 -1300);
DISPLAY INVISIBLE (-975 -1300);
FORCEPROP 1 LAST PATH I86
J 0
(-1025 -1150);
DISPLAY 0.978723 (-1025 -1150);
PAINT WHITE (-1025 -1150);
DISPLAY INVISIBLE (-1025 -1150);
FORCEPROP 0 LAST CDS_LOCATION R4760
J 0
(-1025 -1200);
DISPLAY 1.021277 (-1025 -1200);
DISPLAY INVISIBLE (-1025 -1200);
FORCEPROP 0 LAST $SEC 1
J 0
(-1025 -1200);
DISPLAY 0.680851 (-1025 -1200);
PAINT MONO (-1025 -1200);
DISPLAY INVISIBLE (-1025 -1200);
FORCEPROP 0 LAST CDS_SEC 1
J 0
(-1025 -1200);
DISPLAY 1.021277 (-1025 -1200);
DISPLAY INVISIBLE (-1025 -1200);
FORCEADD OFFPAGE..5
R 2
(550 -1300);
FORCEPROP 2 LAST $XR0 216 
J 0
(739 -1300);
DISPLAY 0.638298 (739 -1300);
PAINT MONO (739 -1300);
FORCEPROP 2 LAST CDS_LIB standard
J 0
(550 -1300);
DISPLAY INVISIBLE (550 -1300);
FORCEPROP 1 LAST OFFPAGE TRUE
J 2
(225 -1425);
DISPLAY 0.872340 (225 -1425);
DISPLAY INVISIBLE (225 -1425);
FORCEPROP 1 LAST COMMENT_BODY TRUE
J 2
(450 -1375);
DISPLAY 1.170213 (450 -1375);
PAINT GREEN (450 -1375);
DISPLAY INVISIBLE (450 -1375);
FORCEPROP 2 LAST PATH I87
J 0
(750 -1250);
DISPLAY 1.021277 (750 -1250);
DISPLAY INVISIBLE (750 -1250);
FORCEADD OFFPAGE..1
(-2275 -1300);
FORCEPROP 2 LAST $XR0 164 
J 0
(-2527 -1300);
DISPLAY 0.638298 (-2527 -1300);
PAINT MONO (-2527 -1300);
FORCEPROP 1 LAST OFFPAGE TRUE
J 0
(-1950 -1425);
DISPLAY 0.872340 (-1950 -1425);
DISPLAY INVISIBLE (-1950 -1425);
FORCEPROP 1 LAST COMMENT_BODY TRUE
J 0
(-2150 -1400);
DISPLAY 1.170213 (-2150 -1400);
PAINT GREEN (-2150 -1400);
DISPLAY INVISIBLE (-2150 -1400);
FORCEPROP 2 LAST CDS_LIB standard
J 2
(-2275 -1300);
DISPLAY INVISIBLE (-2275 -1300);
FORCEPROP 2 LAST PATH I88
J 0
(-2525 -1250);
DISPLAY 1.021277 (-2525 -1250);
DISPLAY INVISIBLE (-2525 -1250);
FORCEADD OFFPAGE..5
R 2
(550 -1475);
FORCEPROP 2 LAST $XR0 216 
J 0
(739 -1475);
DISPLAY 0.638298 (739 -1475);
PAINT MONO (739 -1475);
FORCEPROP 1 LAST OFFPAGE TRUE
J 2
(225 -1600);
DISPLAY 0.872340 (225 -1600);
DISPLAY INVISIBLE (225 -1600);
FORCEPROP 1 LAST COMMENT_BODY TRUE
J 2
(450 -1550);
DISPLAY 1.170213 (450 -1550);
PAINT GREEN (450 -1550);
DISPLAY INVISIBLE (450 -1550);
FORCEPROP 2 LAST PATH I89
J 0
(750 -1425);
DISPLAY 1.021277 (750 -1425);
DISPLAY INVISIBLE (750 -1425);
FORCEPROP 2 LAST CDS_LIB standard
J 0
(550 -1475);
DISPLAY INVISIBLE (550 -1475);
FORCEADD OFFPAGE..2
(950 3325);
FORCEPROP 2 LAST $XR1 219 
J 0
(1259 3325);
DISPLAY 0.638298 (1259 3325);
PAINT MONO (1259 3325);
FORCEPROP 2 LAST $XR0 124 
J 0
(1139 3325);
DISPLAY 0.638298 (1139 3325);
PAINT MONO (1139 3325);
FORCEPROP 2 LAST PATH I9
J 0
(1275 3375);
DISPLAY 1.021277 (1275 3375);
DISPLAY INVISIBLE (1275 3375);
FORCEPROP 2 LAST CDS_LIB standard
J 0
(950 3325);
DISPLAY INVISIBLE (950 3325);
FORCEPROP 1 LAST OFFPAGE TRUE
J 0
(1275 3200);
DISPLAY 1.170213 (1275 3200);
PAINT GREEN (1275 3200);
DISPLAY INVISIBLE (1275 3200);
FORCEPROP 1 LAST COMMENT_BODY TRUE
J 0
(905 3230);
DISPLAY 1.170213 (905 3230);
PAINT GREEN (905 3230);
DISPLAY INVISIBLE (905 3230);
FORCEADD Q_RES..1
(-975 -1475);
FORCEPROP 1 LAST PART_NUMBER CS03322FB03
J 0
(-1125 -1400);
DISPLAY 0.638298 (-1125 -1400);
DISPLAY INVISIBLE (-1125 -1400);
FORCEPROP 1 LAST TOLERANCE 1%
J 0
(-700 -1475);
DISPLAY 0.638298 (-700 -1475);
FORCEPROP 1 LAST VALUE 33.2
J 2
(-725 -1475);
DISPLAY 0.638298 (-725 -1475);
FORCEPROP 1 LAST MATERIAL CHIP
J 0
(-625 -1475);
DISPLAY 0.638298 (-625 -1475);
FORCEPROP 1 LAST $LOCATION R4765
J 0
(-1250 -1475);
DISPLAY 0.638298 (-1250 -1475);
FORCEPROP 1 LASTPIN (-1075 -1475) $PN 1
J 0
(-1063 -1463);
DISPLAY 0.787234 (-1063 -1463);
PAINT MONO (-1063 -1463);
FORCEPROP 1 LASTPIN (-875 -1475) $PN 2
J 0
(-913 -1463);
DISPLAY 0.787234 (-913 -1463);
PAINT MONO (-913 -1463);
FORCEPROP 1 LAST PACK_TYPE 0402LF
J 0
(-1125 -1350);
DISPLAY 0.638298 (-1125 -1350);
DISPLAY INVISIBLE (-1125 -1350);
FORCEPROP 1 LAST WATTAGE 1/16W
J 2
(-775 -1350);
DISPLAY 0.638298 (-775 -1350);
DISPLAY INVISIBLE (-775 -1350);
FORCEPROP 1 LAST PATH I90
J 0
(-1025 -1325);
DISPLAY 0.978723 (-1025 -1325);
PAINT WHITE (-1025 -1325);
DISPLAY INVISIBLE (-1025 -1325);
FORCEPROP 2 LAST CDS_LIB pure_quanta
J 0
(-975 -1475);
DISPLAY INVISIBLE (-975 -1475);
FORCEPROP 0 LAST CDS_LOCATION R4765
J 0
(-1025 -1375);
DISPLAY 1.021277 (-1025 -1375);
DISPLAY INVISIBLE (-1025 -1375);
FORCEPROP 0 LAST $SEC 1
J 0
(-1025 -1375);
DISPLAY 0.680851 (-1025 -1375);
PAINT MONO (-1025 -1375);
DISPLAY INVISIBLE (-1025 -1375);
FORCEPROP 0 LAST CDS_SEC 1
J 0
(-1025 -1375);
DISPLAY 1.021277 (-1025 -1375);
DISPLAY INVISIBLE (-1025 -1375);
FORCEADD OFFPAGE..1
(-2275 -1475);
FORCEPROP 2 LAST $XR1 193 
J 0
(-2647 -1475);
DISPLAY 0.638298 (-2647 -1475);
PAINT MONO (-2647 -1475);
FORCEPROP 2 LAST $XR0 192 
J 0
(-2527 -1475);
DISPLAY 0.638298 (-2527 -1475);
PAINT MONO (-2527 -1475);
FORCEPROP 1 LAST OFFPAGE TRUE
J 0
(-1950 -1600);
DISPLAY 0.872340 (-1950 -1600);
DISPLAY INVISIBLE (-1950 -1600);
FORCEPROP 1 LAST COMMENT_BODY TRUE
J 0
(-2150 -1575);
DISPLAY 1.170213 (-2150 -1575);
PAINT GREEN (-2150 -1575);
DISPLAY INVISIBLE (-2150 -1575);
FORCEPROP 2 LAST PATH I91
J 0
(-2525 -1425);
DISPLAY 1.021277 (-2525 -1425);
DISPLAY INVISIBLE (-2525 -1425);
FORCEPROP 2 LAST CDS_LIB standard
J 2
(-2275 -1475);
DISPLAY INVISIBLE (-2275 -1475);
FORCEADD OFFPAGE..1
(-2600 1125);
FORCEPROP 2 LAST $XR0 216 
J 0
(-2852 1125);
DISPLAY 0.638298 (-2852 1125);
PAINT MONO (-2852 1125);
FORCEPROP 1 LAST COMMENT_BODY TRUE
J 0
(-2475 1025);
DISPLAY 1.170213 (-2475 1025);
PAINT GREEN (-2475 1025);
DISPLAY INVISIBLE (-2475 1025);
FORCEPROP 1 LAST OFFPAGE TRUE
J 0
(-2275 1000);
DISPLAY 1.170213 (-2275 1000);
PAINT GREEN (-2275 1000);
DISPLAY INVISIBLE (-2275 1000);
FORCEPROP 2 LAST PATH I92
J 0
(-2550 1200);
DISPLAY 1.021277 (-2550 1200);
DISPLAY INVISIBLE (-2550 1200);
FORCEPROP 2 LAST CDS_LIB standard
J 0
(-2600 1125);
DISPLAY INVISIBLE (-2600 1125);
FORCEADD OFFPAGE..1
(-2600 1075);
FORCEPROP 2 LAST $XR0 191 
J 0
(-2852 1075);
DISPLAY 0.638298 (-2852 1075);
PAINT MONO (-2852 1075);
FORCEPROP 2 LAST CDS_LIB standard
J 0
(-2600 1075);
DISPLAY INVISIBLE (-2600 1075);
FORCEPROP 2 LAST PATH I93
J 0
(-2550 1150);
DISPLAY 1.021277 (-2550 1150);
DISPLAY INVISIBLE (-2550 1150);
FORCEPROP 1 LAST OFFPAGE TRUE
J 0
(-2275 950);
DISPLAY 1.170213 (-2275 950);
PAINT GREEN (-2275 950);
DISPLAY INVISIBLE (-2275 950);
FORCEPROP 1 LAST COMMENT_BODY TRUE
J 0
(-2475 975);
DISPLAY 1.170213 (-2475 975);
PAINT GREEN (-2475 975);
DISPLAY INVISIBLE (-2475 975);
FORCEADD OFFPAGE..5
(-2600 1025);
FORCEPROP 2 LAST $XR0 183 
J 0
(-2885 1025);
DISPLAY 0.638298 (-2885 1025);
PAINT MONO (-2885 1025);
FORCEPROP 2 LAST PATH I94
J 0
(-2550 1100);
DISPLAY 1.021277 (-2550 1100);
DISPLAY INVISIBLE (-2550 1100);
FORCEPROP 2 LAST CDS_LIB standard
J 0
(-2600 1025);
DISPLAY INVISIBLE (-2600 1025);
FORCEPROP 1 LAST OFFPAGE TRUE
J 0
(-2275 900);
DISPLAY 0.872340 (-2275 900);
DISPLAY INVISIBLE (-2275 900);
FORCEPROP 1 LAST COMMENT_BODY TRUE
J 0
(-2500 950);
DISPLAY 1.170213 (-2500 950);
PAINT GREEN (-2500 950);
DISPLAY INVISIBLE (-2500 950);
FORCEADD Q_RES..1
(-975 -1625);
FORCEPROP 1 LAST PART_NUMBER CS03322FB03
J 0
(-1125 -1550);
DISPLAY 0.638298 (-1125 -1550);
DISPLAY INVISIBLE (-1125 -1550);
FORCEPROP 1 LAST MATERIAL CHIP
J 0
(-625 -1625);
DISPLAY 0.638298 (-625 -1625);
FORCEPROP 1 LAST TOLERANCE 1%
J 0
(-700 -1625);
DISPLAY 0.638298 (-700 -1625);
FORCEPROP 1 LAST VALUE 33.2
J 2
(-725 -1625);
DISPLAY 0.638298 (-725 -1625);
FORCEPROP 1 LAST $LOCATION R4771
J 0
(-1200 -1625);
DISPLAY 0.787234 (-1200 -1625);
FORCEPROP 1 LASTPIN (-1075 -1625) $PN 1
J 0
(-1063 -1613);
DISPLAY 0.787234 (-1063 -1613);
PAINT MONO (-1063 -1613);
FORCEPROP 1 LASTPIN (-875 -1625) $PN 2
J 0
(-913 -1613);
DISPLAY 0.787234 (-913 -1613);
PAINT MONO (-913 -1613);
FORCEPROP 2 LAST CDS_LIB pure_quanta
J 0
(-975 -1625);
DISPLAY INVISIBLE (-975 -1625);
FORCEPROP 1 LAST PATH I95
J 0
(-1025 -1475);
DISPLAY 0.978723 (-1025 -1475);
PAINT WHITE (-1025 -1475);
DISPLAY INVISIBLE (-1025 -1475);
FORCEPROP 1 LAST PACK_TYPE 0402LF
J 0
(-1125 -1500);
DISPLAY 0.638298 (-1125 -1500);
DISPLAY INVISIBLE (-1125 -1500);
FORCEPROP 1 LAST WATTAGE 1/16W
J 2
(-775 -1500);
DISPLAY 0.638298 (-775 -1500);
DISPLAY INVISIBLE (-775 -1500);
FORCEPROP 0 LAST CDS_LOCATION R4771
J 0
(-625 -1575);
DISPLAY 1.021277 (-625 -1575);
DISPLAY INVISIBLE (-625 -1575);
FORCEPROP 0 LAST $SEC 1
J 0
(-625 -1575);
DISPLAY 0.680851 (-625 -1575);
PAINT MONO (-625 -1575);
DISPLAY INVISIBLE (-625 -1575);
FORCEPROP 0 LAST CDS_SEC 1
J 0
(-625 -1575);
DISPLAY 1.021277 (-625 -1575);
DISPLAY INVISIBLE (-625 -1575);
FORCEADD OFFPAGE..1
(-2300 -1625);
FORCEPROP 2 LAST $XR0 242 
J 0
(-2552 -1625);
DISPLAY 0.638298 (-2552 -1625);
PAINT MONO (-2552 -1625);
FORCEPROP 1 LAST COMMENT_BODY TRUE
J 0
(-2175 -1725);
DISPLAY 1.170213 (-2175 -1725);
PAINT GREEN (-2175 -1725);
DISPLAY INVISIBLE (-2175 -1725);
FORCEPROP 1 LAST OFFPAGE TRUE
J 0
(-1975 -1750);
DISPLAY 0.872340 (-1975 -1750);
DISPLAY INVISIBLE (-1975 -1750);
FORCEPROP 2 LAST PATH I96
J 0
(-2250 -1550);
DISPLAY 1.021277 (-2250 -1550);
DISPLAY INVISIBLE (-2250 -1550);
FORCEPROP 2 LAST CDS_LIB standard
J 0
(-2300 -1625);
DISPLAY INVISIBLE (-2300 -1625);
FORCEADD OFFPAGE..5
R 2
(550 -1625);
FORCEPROP 2 LAST $XR0 216 
J 0
(739 -1625);
DISPLAY 0.638298 (739 -1625);
PAINT MONO (739 -1625);
FORCEPROP 1 LAST COMMENT_BODY TRUE
J 2
(450 -1700);
DISPLAY 1.170213 (450 -1700);
PAINT GREEN (450 -1700);
DISPLAY INVISIBLE (450 -1700);
FORCEPROP 1 LAST OFFPAGE TRUE
J 2
(225 -1750);
DISPLAY 0.872340 (225 -1750);
DISPLAY INVISIBLE (225 -1750);
FORCEPROP 2 LAST PATH I97
J 0
(725 -1550);
DISPLAY 1.021277 (725 -1550);
DISPLAY INVISIBLE (725 -1550);
FORCEPROP 2 LAST CDS_LIB standard
J 0
(550 -1625);
DISPLAY INVISIBLE (550 -1625);
FORCEADD OFFPAGE..1
(-2600 975);
FORCEPROP 2 LAST $XR0 216 
J 0
(-2882 975);
DISPLAY 0.638298 (-2882 975);
PAINT MONO (-2882 975);
FORCEPROP 2 LAST CDS_LIB standard
J 0
(-2600 975);
DISPLAY INVISIBLE (-2600 975);
FORCEPROP 2 LAST PATH I98
J 0
(-2550 1050);
DISPLAY 1.021277 (-2550 1050);
DISPLAY INVISIBLE (-2550 1050);
FORCEPROP 1 LAST COMMENT_BODY TRUE
J 0
(-2475 875);
DISPLAY 1.170213 (-2475 875);
PAINT GREEN (-2475 875);
DISPLAY INVISIBLE (-2475 875);
FORCEPROP 1 LAST OFFPAGE TRUE
J 0
(-2275 850);
DISPLAY 1.170213 (-2275 850);
PAINT GREEN (-2275 850);
DISPLAY INVISIBLE (-2275 850);
FORCEADD DESIGN_NOTE..1
(3050 2675);
FORCEPROP 0 LAST S2 PERST FROM PLTRST_N (DEFAULT)
J 0
(2875 2425);
DISPLAY 1.021277 (2875 2425);
PAINT SKYBLUE (2875 2425);
FORCEPROP 0 LAST S3 PERST FROM CPUPWRGD
J 0
(2875 2325);
DISPLAY 1.021277 (2875 2325);
PAINT SKYBLUE (2875 2325);
FORCEPROP 0 LAST S1 BIT0/1/2
J 0
(2875 2525);
DISPLAY 1.021277 (2875 2525);
PAINT SKYBLUE (2875 2525);
FORCEPROP 2 LAST CDS_LIB logical_power
J 0
(3050 2675);
PAINT MONO (3050 2675);
DISPLAY INVISIBLE (3050 2675);
FORCEPROP 1 LAST COMMENT_BODY TRUE
J 0
(3075 2775);
DISPLAY 0.978723 (3075 2775);
DISPLAY INVISIBLE (3075 2775);
FORCEADD QUANTA_TITLE_BLOCK_C..1
(4900 -2400);
FORCEPROP 0 LAST CDS_CON_LAST_MODIFIED Fri Aug 25 14:03:35 2023
J 0
(3015 -2385);
PAINT MONO (3015 -2385);
DISPLAY INVISIBLE (3015 -2385);
FORCEPROP 2 LAST CUSTOM_TXT_CDS <XR_PAGE_TITLE>
J 0
(-2990 2850);
DISPLAY 0.638298 (-2990 2850);
PAINT PINK (-2990 2850);
DISPLAY INVISIBLE (-2990 2850);
FORCEPROP 2 LAST CUSTOM_TXT_CDS <CON_LAST_MODIFIED>
J 0
(3050 -2400);
DISPLAY 0.978723 (3050 -2400);
FORCEPROP 2 LAST CUSTOM_TXT_CDS <NAME_1>
J 0
(1725 -2225);
FORCEPROP 2 LAST CUSTOM_TXT_CDS <CON_PAGE_NUM> OF <CON_TOTAL_PAGES>
J 0
(4454 -2382);
DISPLAY 0.978723 (4454 -2382);
FORCEPROP 2 LAST CUSTOM_TXT_CDS <NAME_2>
J 0
(1725 -2350);
FORCEPROP 2 LAST CUSTOM_TXT_CDS <Q_PROJ>
J 0
(2518 -2298);
DISPLAY 1.212766 (2518 -2298);
FORCEPROP 2 LAST CUSTOM_TXT_CDS <Q_NUMBER>
J 0
(3497 -2297);
DISPLAY 1.212766 (3497 -2297);
FORCEPROP 2 LAST CUSTOM_TXT_CDS <Q_REV>
J 0
(4716 -2297);
DISPLAY 1.212766 (4716 -2297);
FORCEPROP 1 LAST Q_TITLE MAIN FPGA / PFR (4/5)
J 0
(-4441 -2374);
DISPLAY 1.957447 (-4441 -2374);
PAINT GREEN (-4441 -2374);
FORCEPROP 1 LAST Q_DEPT 
J 1
(1137 -2351);
DISPLAY 1.957447 (1137 -2351);
PAINT GREEN (1137 -2351);
FORCEPROP 2 LAST CDS_XR_PAGE_TITLE CR-216 : @S9S_MB_2U_LIB.S9S_MB_2U(SCH_1):PAGE216
J 0
(-2990 2850);
DISPLAY 0.638298 (-2990 2850);
PAINT PINK (-2990 2850);
DISPLAY INVISIBLE (-2990 2850);
FORCEPROP 2 LAST CDS_LIB pure_quanta
J 0
(4900 -2400);
PAINT MONO (4900 -2400);
DISPLAY INVISIBLE (4900 -2400);
FORCEPROP 1 LAST CDS_LMAN_SYM_OUTLINE -9475,6775,100,-125
J 0
(4900 -2400);
DISPLAY 0.468085 (4900 -2400);
PAINT GREEN (4900 -2400);
DISPLAY INVISIBLE (4900 -2400);
FORCEPROP 2 LAST PAGE_BORDER TRUE
J 0
(-2990 2850);
DISPLAY 0.638298 (-2990 2850);
PAINT PINK (-2990 2850);
DISPLAY INVISIBLE (-2990 2850);
FORCEPROP 1 LAST COMMENT_BODY TRUE
J 0
(4912 -2413);
DISPLAY 0.978723 (4912 -2413);
PAINT GREEN (4912 -2413);
DISPLAY INVISIBLE (4912 -2413);
WIRE 16 -1 (4175 3450)(4175 3525);
WIRE 16 -1 (1300 150)(1300 300);
WIRE 16 -1 (500 -1625)(-875 -1625);
FORCEPROP 2 LAST SIG_NAME HP_LVC3_SCM_HSC_PWRGD_PLD
J 0
(-385 -1615);
DISPLAY 0.638298 (-385 -1615);
WIRE 16 -1 (-2225 -1150)(-1075 -1150);
FORCEPROP 0 LAST CDS_PHYS_NET_NAME HP_LVC3_OCP_V3_1_PWRGD_R
J 0
(-2110 -1108);
PAINT MONO (-2110 -1108);
DISPLAY INVISIBLE (-2110 -1108);
FORCEPROP 2 LAST SIG_NAME HP_LVC3_OCP_V3_1_PWRGD_R
J 0
(-2060 -1140);
DISPLAY 0.553191 (-2060 -1140);
PAINT WHITE (-2060 -1140);
FORCEPROP 0 LAST $PHYS_NET_NAME RST_PCIE_M2_N
J 0
(-2110 -1061);
PAINT MONO (-2110 -1061);
DISPLAY INVISIBLE (-2110 -1061);
WIRE 16 -1 (-2225 -1300)(-1075 -1300);
FORCEPROP 0 LAST CDS_PHYS_NET_NAME HP_LVC3_OCP_V3_1_PWRGD_R
J 0
(-2110 -1258);
PAINT MONO (-2110 -1258);
DISPLAY INVISIBLE (-2110 -1258);
FORCEPROP 2 LAST SIG_NAME HP_LVC3_OCP_V3_2_PWRGD_R
J 0
(-2060 -1290);
DISPLAY 0.553191 (-2060 -1290);
PAINT WHITE (-2060 -1290);
FORCEPROP 0 LAST $PHYS_NET_NAME RST_PCIE_M2_N
J 0
(-2110 -1211);
PAINT MONO (-2110 -1211);
DISPLAY INVISIBLE (-2110 -1211);
WIRE 16 -1 (-2225 -1475)(-1075 -1475);
FORCEPROP 0 LAST CDS_PHYS_NET_NAME HP_LVC3_OCP_V3_1_PWRGD_R
J 0
(-2110 -1433);
PAINT MONO (-2110 -1433);
DISPLAY INVISIBLE (-2110 -1433);
FORCEPROP 2 LAST SIG_NAME HP_LVC3_E1S_0_HSC_PWRGD
J 0
(-2060 -1465);
DISPLAY 0.553191 (-2060 -1465);
PAINT WHITE (-2060 -1465);
FORCEPROP 0 LAST $PHYS_NET_NAME RST_PCIE_M2_N
J 0
(-2110 -1386);
PAINT MONO (-2110 -1386);
DISPLAY INVISIBLE (-2110 -1386);
WIRE 16 -1 (-1075 -1625)(-2250 -1625);
FORCEPROP 2 LAST SIG_NAME HP_LVC3_SCM_HSC_PWRGD
J 0
(-2060 -1615);
DISPLAY 0.638298 (-2060 -1615);
WIRE 16 -1 (-1525 975)(-2550 975);
FORCEPROP 2 LAST SIG_NAME HP_LVC3_SCM_HSC_PWRGD_PLD
J 0
(-2510 985);
DISPLAY 0.638298 (-2510 985);
WIRE 16 -1 (-1525 1075)(-2550 1075);
FORCEPROP 2 LAST SIG_NAME HP_E1S_0_P3V3_PWRGD_PLD
J 0
(-2510 1085);
DISPLAY 0.553191 (-2510 1085);
PAINT WHITE (-2510 1085);
WIRE 16 -1 (-2550 1125)(-1525 1125);
FORCEPROP 0 LAST CDS_PHYS_NET_NAME HP_LVC3_OCP_V3_1_PWRGD_R
J 0
(-2435 1167);
PAINT MONO (-2435 1167);
DISPLAY INVISIBLE (-2435 1167);
FORCEPROP 2 LAST SIG_NAME HP_LVC3_E1S_0_HSC_PWRGD_PLD
J 0
(-2510 1135);
DISPLAY 0.553191 (-2510 1135);
PAINT WHITE (-2510 1135);
FORCEPROP 0 LAST $PHYS_NET_NAME RST_PCIE_M2_N
J 0
(-2435 1214);
PAINT MONO (-2435 1214);
DISPLAY INVISIBLE (-2435 1214);
WIRE 16 -1 (-875 -1475)(500 -1475);
FORCEPROP 0 LAST CDS_PHYS_NET_NAME HP_LVC3_OCP_V3_1_PWRGD_R
J 0
(-760 -1433);
PAINT MONO (-760 -1433);
DISPLAY INVISIBLE (-760 -1433);
FORCEPROP 2 LAST SIG_NAME HP_LVC3_E1S_0_HSC_PWRGD_PLD
J 0
(-410 -1465);
DISPLAY 0.553191 (-410 -1465);
PAINT WHITE (-410 -1465);
FORCEPROP 0 LAST $PHYS_NET_NAME RST_PCIE_M2_N
J 0
(-760 -1386);
PAINT MONO (-760 -1386);
DISPLAY INVISIBLE (-760 -1386);
WIRE 16 -1 (-2550 1025)(-1525 1025);
FORCEPROP 2 LAST SIG_NAME E1S_0_CLK_OE_N
J 0
(-2510 1035);
DISPLAY 0.553191 (-2510 1035);
PAINT WHITE (-2510 1035);
WIRE 16 -1 (-375 -225)(1300 -225);
FORCEPROP 2 LAST SIG_NAME PU_FPGA_D12_PROGRAMN
J 0
(-210 -215);
DISPLAY 0.638298 (-210 -215);
PAINT WHITE (-210 -215);
WIRE 16 -1 (1300 -225)(1300 -50);
WIRE 16 -1 (-375 -175)(825 -175);
FORCEPROP 0 LAST CDS_PHYS_NET_NAME JTAG_PLD_JTAGEN
J 0
(-350 -133);
PAINT MONO (-350 -133);
DISPLAY INVISIBLE (-350 -133);
FORCEPROP 0 LAST SIG_NAME JTAG_PLD_JTAGEN
J 0
(-210 -165);
DISPLAY 0.680851 (-210 -165);
PAINT WHITE (-210 -165);
WIRE 16 -1 (-375 -125)(825 -125);
FORCEPROP 0 LAST CDS_PHYS_NET_NAME JTAG_PLD_TMS_R
J 0
(-350 -83);
PAINT MONO (-350 -83);
DISPLAY INVISIBLE (-350 -83);
FORCEPROP 0 LAST SIG_NAME JTAG_PLD_TMS_R
J 0
(-210 -115);
DISPLAY 0.680851 (-210 -115);
PAINT WHITE (-210 -115);
WIRE 16 -1 (-375 -75)(825 -75);
FORCEPROP 0 LAST CDS_PHYS_NET_NAME JTAG_PLD_TCK_R
J 0
(-350 -33);
PAINT MONO (-350 -33);
DISPLAY INVISIBLE (-350 -33);
FORCEPROP 0 LAST SIG_NAME JTAG_PLD_TCK_R
J 0
(-210 -65);
DISPLAY 0.680851 (-210 -65);
PAINT WHITE (-210 -65);
WIRE 16 -1 (-375 -275)(775 -275);
FORCEPROP 0 LAST CDS_PHYS_NET_NAME PWRGD_PCH_PWROK_R
J 0
(-350 -233);
PAINT MONO (-350 -233);
DISPLAY INVISIBLE (-350 -233);
FORCEPROP 0 LAST SIG_NAME NC_FPGA_PT44C
J 0
(-210 -265);
DISPLAY 0.680851 (-210 -265);
PAINT WHITE (-210 -265);
WIRE 16 -1 (-375 -325)(775 -325);
FORCEPROP 0 LAST CDS_PHYS_NET_NAME PWRGD_PCH_PWROK_R
J 0
(-350 -283);
PAINT MONO (-350 -283);
DISPLAY INVISIBLE (-350 -283);
FORCEPROP 0 LAST SIG_NAME NC_FPGA_PT44D
J 0
(-210 -315);
DISPLAY 0.680851 (-210 -315);
PAINT WHITE (-210 -315);
WIRE 16 -1 (-875 -1300)(500 -1300);
FORCEPROP 0 LAST CDS_PHYS_NET_NAME HP_LVC3_OCP_V3_1_PWRGD_R
J 0
(-760 -1258);
PAINT MONO (-760 -1258);
DISPLAY INVISIBLE (-760 -1258);
FORCEPROP 2 LAST SIG_NAME HP_LVC3_OCP_V3_2_FUSE_PWRGD
J 0
(-410 -1290);
DISPLAY 0.553191 (-410 -1290);
PAINT WHITE (-410 -1290);
FORCEPROP 0 LAST $PHYS_NET_NAME RST_PCIE_M2_N
J 0
(-760 -1211);
PAINT MONO (-760 -1211);
DISPLAY INVISIBLE (-760 -1211);
WIRE 16 -1 (-875 -1150)(500 -1150);
FORCEPROP 0 LAST CDS_PHYS_NET_NAME HP_LVC3_OCP_V3_1_PWRGD_R
J 0
(-760 -1108);
PAINT MONO (-760 -1108);
DISPLAY INVISIBLE (-760 -1108);
FORCEPROP 2 LAST SIG_NAME HP_LVC3_OCP_V3_1_FUSE_PWRGD
J 0
(-410 -1140);
DISPLAY 0.553191 (-410 -1140);
PAINT WHITE (-410 -1140);
FORCEPROP 0 LAST $PHYS_NET_NAME RST_PCIE_M2_N
J 0
(-760 -1061);
PAINT MONO (-760 -1061);
DISPLAY INVISIBLE (-760 -1061);
WIRE 16 -1 (-1525 1175)(-2550 1175);
FORCEPROP 0 LAST CDS_PHYS_NET_NAME HP_LVC3_OCP_V3_2_PRSNT2_PLD_N
J 0
(-1635 1217);
PAINT MONO (-1635 1217);
DISPLAY INVISIBLE (-1635 1217);
FORCEPROP 2 LAST SIG_NAME HP_LVC3_OCP_V3_2_PRSNT2_PLD_N
J 0
(-2510 1185);
DISPLAY 0.553191 (-2510 1185);
PAINT WHITE (-2510 1185);
WIRE 16 -1 (-1525 1225)(-2550 1225);
FORCEPROP 0 LAST CDS_PHYS_NET_NAME HP_LVC3_OCP_V3_1_PRSNT2_N
J 0
(-1635 1267);
PAINT MONO (-1635 1267);
DISPLAY INVISIBLE (-1635 1267);
FORCEPROP 2 LAST SIG_NAME HP_LVC3_OCP_V3_1_PRSNT2_PLD_N
J 0
(-2510 1235);
DISPLAY 0.553191 (-2510 1235);
PAINT WHITE (-2510 1235);
WIRE 16 -1 (-2550 1275)(-1525 1275);
FORCEPROP 0 LAST CDS_PHYS_NET_NAME HP_LVC3_OCP_V3_2_PWRGD_R
J 0
(-2235 1317);
PAINT MONO (-2235 1317);
DISPLAY INVISIBLE (-2235 1317);
FORCEPROP 2 LAST SIG_NAME HP_LVC3_OCP_V3_2_FUSE_PWRGD
J 0
(-2510 1285);
DISPLAY 0.553191 (-2510 1285);
PAINT WHITE (-2510 1285);
FORCEPROP 0 LAST $PHYS_NET_NAME RST_PCIE_M2_N
J 0
(-2235 1364);
PAINT MONO (-2235 1364);
DISPLAY INVISIBLE (-2235 1364);
WIRE 16 -1 (-2550 1325)(-1525 1325);
FORCEPROP 0 LAST CDS_PHYS_NET_NAME HP_LVC3_OCP_V3_1_PWRGD_R
J 0
(-2435 1367);
PAINT MONO (-2435 1367);
DISPLAY INVISIBLE (-2435 1367);
FORCEPROP 2 LAST SIG_NAME HP_LVC3_OCP_V3_1_FUSE_PWRGD
J 0
(-2510 1335);
DISPLAY 0.553191 (-2510 1335);
PAINT WHITE (-2510 1335);
FORCEPROP 0 LAST $PHYS_NET_NAME RST_PCIE_M2_N
J 0
(-2435 1414);
PAINT MONO (-2435 1414);
DISPLAY INVISIBLE (-2435 1414);
WIRE 16 -1 (-2525 3375)(-1525 3375);
FORCEPROP 0 LAST CDS_PHYS_NET_NAME RST_CPU0_DRAM_CD_PLD_N
J 0
(-2500 3417);
PAINT MONO (-2500 3417);
DISPLAY INVISIBLE (-2500 3417);
FORCEPROP 0 LAST SIG_NAME RST_CPU0_DRAM_CD_PLD_LVT3_N
J 0
(-2510 3385);
DISPLAY 0.680851 (-2510 3385);
PAINT WHITE (-2510 3385);
WIRE 16 -1 (-2525 3175)(-1525 3175);
FORCEPROP 0 LAST CDS_PHYS_NET_NAME RST_CPU1_DRAM_CD_PLD_N
J 0
(-2500 3217);
PAINT MONO (-2500 3217);
DISPLAY INVISIBLE (-2500 3217);
FORCEPROP 0 LAST SIG_NAME RST_CPU1_DRAM_CD_PLD_LVT3_N
J 0
(-2510 3185);
DISPLAY 0.680851 (-2510 3185);
PAINT WHITE (-2510 3185);
WIRE 16 -1 (-2525 3275)(-1525 3275);
FORCEPROP 0 LAST CDS_PHYS_NET_NAME RST_CPU0_DRAM_GH_PLD_N
J 0
(-2500 3317);
PAINT MONO (-2500 3317);
DISPLAY INVISIBLE (-2500 3317);
FORCEPROP 0 LAST SIG_NAME RST_CPU0_DRAM_GH_PLD_LVT3_N
J 0
(-2510 3285);
DISPLAY 0.680851 (-2510 3285);
PAINT WHITE (-2510 3285);
WIRE 16 -1 (-2525 2775)(-1525 2775);
FORCEPROP 0 LAST CDS_PHYS_NET_NAME RST_PLD_CPU1_DRAM_CD_N
J 0
(-2500 2817);
PAINT MONO (-2500 2817);
DISPLAY INVISIBLE (-2500 2817);
FORCEPROP 0 LAST SIG_NAME RST_PLD_CPU1_DRAM_CD_N
J 0
(-2510 2785);
DISPLAY 0.680851 (-2510 2785);
PAINT GREEN (-2510 2785);
WIRE 16 -1 (3125 3125)(4175 3125);
FORCEPROP 0 LAST CDS_PHYS_NET_NAME RST_MB_STBY_R_N
J 0
(3150 3167);
PAINT MONO (3150 3167);
DISPLAY INVISIBLE (3150 3167);
FORCEPROP 0 LAST SIG_NAME RST_MB_STBY_R_N
J 0
(3300 3135);
DISPLAY 0.680851 (3300 3135);
PAINT WHITE (3300 3135);
WIRE 16 -1 (4175 3250)(4175 3125);
WIRE 16 -1 (-2525 3225)(-1525 3225);
FORCEPROP 0 LAST CDS_PHYS_NET_NAME RST_CPU1_DRAM_AB_PLD_N
J 0
(-2500 3267);
PAINT MONO (-2500 3267);
DISPLAY INVISIBLE (-2500 3267);
FORCEPROP 0 LAST SIG_NAME RST_CPU1_DRAM_AB_PLD_LVT3_N
J 0
(-2510 3235);
DISPLAY 0.680851 (-2510 3235);
PAINT WHITE (-2510 3235);
WIRE 16 -1 (-2525 3075)(-1525 3075);
FORCEPROP 0 LAST CDS_PHYS_NET_NAME RST_CPU1_DRAM_GH_PLD_N
J 0
(-2500 3117);
PAINT MONO (-2500 3117);
DISPLAY INVISIBLE (-2500 3117);
FORCEPROP 0 LAST SIG_NAME RST_CPU1_DRAM_GH_PLD_LVT3_N
J 0
(-2510 3085);
DISPLAY 0.680851 (-2510 3085);
PAINT WHITE (-2510 3085);
WIRE 16 -1 (-2525 2975)(-1525 2975);
FORCEPROP 0 LAST CDS_PHYS_NET_NAME RST_PLD_CPU0_DRAM_CD_N
J 0
(-2500 3017);
PAINT MONO (-2500 3017);
DISPLAY INVISIBLE (-2500 3017);
FORCEPROP 0 LAST SIG_NAME RST_PLD_CPU0_DRAM_CD_N
J 0
(-2510 2985);
DISPLAY 0.680851 (-2510 2985);
PAINT GREEN (-2510 2985);
WIRE 16 -1 (-2525 3325)(-1525 3325);
FORCEPROP 0 LAST CDS_PHYS_NET_NAME RST_CPU0_DRAM_EF_PLD_N
J 0
(-2500 3367);
PAINT MONO (-2500 3367);
DISPLAY INVISIBLE (-2500 3367);
FORCEPROP 0 LAST SIG_NAME RST_CPU0_DRAM_EF_PLD_LVT3_N
J 0
(-2510 3335);
DISPLAY 0.680851 (-2510 3335);
PAINT WHITE (-2510 3335);
WIRE 16 -1 (-2525 3425)(-1525 3425);
FORCEPROP 0 LAST CDS_PHYS_NET_NAME RST_CPU0_DRAM_AB_PLD_N
J 0
(-2500 3467);
PAINT MONO (-2500 3467);
DISPLAY INVISIBLE (-2500 3467);
FORCEPROP 0 LAST SIG_NAME RST_CPU0_DRAM_AB_PLD_LVT3_N
J 0
(-2510 3435);
DISPLAY 0.680851 (-2510 3435);
PAINT WHITE (-2510 3435);
WIRE 16 -1 (-2525 3125)(-1525 3125);
FORCEPROP 0 LAST CDS_PHYS_NET_NAME RST_CPU1_DRAM_EF_PLD_N
J 0
(-2500 3167);
PAINT MONO (-2500 3167);
DISPLAY INVISIBLE (-2500 3167);
FORCEPROP 0 LAST SIG_NAME RST_CPU1_DRAM_EF_PLD_LVT3_N
J 0
(-2510 3135);
DISPLAY 0.680851 (-2510 3135);
PAINT WHITE (-2510 3135);
WIRE 16 -1 (-2525 3025)(-1525 3025);
FORCEPROP 0 LAST CDS_PHYS_NET_NAME RST_PLD_CPU0_DRAM_AB_N
J 0
(-2500 3067);
PAINT MONO (-2500 3067);
DISPLAY INVISIBLE (-2500 3067);
FORCEPROP 0 LAST SIG_NAME RST_PLD_CPU0_DRAM_AB_N
J 0
(-2510 3035);
DISPLAY 0.680851 (-2510 3035);
PAINT GREEN (-2510 3035);
WIRE 16 -1 (-2525 2925)(-1525 2925);
FORCEPROP 0 LAST CDS_PHYS_NET_NAME RST_PLD_CPU0_DRAM_EF_N
J 0
(-2500 2967);
PAINT MONO (-2500 2967);
DISPLAY INVISIBLE (-2500 2967);
FORCEPROP 0 LAST SIG_NAME RST_PLD_CPU0_DRAM_EF_N
J 0
(-2510 2935);
DISPLAY 0.680851 (-2510 2935);
PAINT GREEN (-2510 2935);
WIRE 16 -1 (-2525 2875)(-1525 2875);
FORCEPROP 0 LAST CDS_PHYS_NET_NAME RST_PLD_CPU0_DRAM_GH_N
J 0
(-2500 2917);
PAINT MONO (-2500 2917);
DISPLAY INVISIBLE (-2500 2917);
FORCEPROP 0 LAST SIG_NAME RST_PLD_CPU0_DRAM_GH_N
J 0
(-2510 2885);
DISPLAY 0.680851 (-2510 2885);
PAINT GREEN (-2510 2885);
WIRE 16 -1 (-2525 2825)(-1525 2825);
FORCEPROP 0 LAST CDS_PHYS_NET_NAME RST_PLD_CPU1_DRAM_AB_N
J 0
(-2500 2867);
PAINT MONO (-2500 2867);
DISPLAY INVISIBLE (-2500 2867);
FORCEPROP 0 LAST SIG_NAME RST_PLD_CPU1_DRAM_AB_N
J 0
(-2510 2835);
DISPLAY 0.680851 (-2510 2835);
PAINT GREEN (-2510 2835);
WIRE 16 -1 (-2550 2225)(-1525 2225);
FORCEPROP 0 LAST CDS_PHYS_NET_NAME H_CPU0_MEMHOT_OUT_LVC1_N
J 0
(-2525 2267);
PAINT MONO (-2525 2267);
DISPLAY INVISIBLE (-2525 2267);
FORCEPROP 0 LAST SIG_NAME H_CPU0_MEMHOT_OUT_LVC1_N
J 0
(-2560 2235);
DISPLAY 0.680851 (-2560 2235);
PAINT WHITE (-2560 2235);
WIRE 16 -1 (-2550 2025)(-1525 2025);
FORCEPROP 0 LAST CDS_PHYS_NET_NAME H_CPU0_THERMTRIP_LVC1_N
J 0
(-2525 2067);
PAINT MONO (-2525 2067);
DISPLAY INVISIBLE (-2525 2067);
FORCEPROP 0 LAST SIG_NAME H_CPU0_THERMTRIP_LVC1_N
J 0
(-2560 2035);
DISPLAY 0.680851 (-2560 2035);
PAINT WHITE (-2560 2035);
WIRE 16 -1 (-225 3425)(900 3425);
FORCEPROP 0 LAST CDS_PHYS_NET_NAME PWRGD_DRAMPWRGD_CPU0_AB_R_LVC1
J 0
(-200 3467);
PAINT MONO (-200 3467);
DISPLAY INVISIBLE (-200 3467);
FORCEPROP 0 LAST SIG_NAME PWRGD_DRAMPWRGD_CPU0_AB_R_LVC1
J 0
(-135 3435);
DISPLAY 0.680851 (-135 3435);
PAINT GREEN (-135 3435);
WIRE 16 -1 (-225 3375)(900 3375);
FORCEPROP 0 LAST CDS_PHYS_NET_NAME PWRGD_DRAMPWRGD_CPU0_CD_R_LVC1
J 0
(-200 3417);
PAINT MONO (-200 3417);
DISPLAY INVISIBLE (-200 3417);
FORCEPROP 0 LAST SIG_NAME PWRGD_DRAMPWRGD_CPU0_CD_R_LVC1
J 0
(-135 3385);
DISPLAY 0.680851 (-135 3385);
PAINT GREEN (-135 3385);
WIRE 16 -1 (725 2325)(-225 2325);
FORCEPROP 0 LAST CDS_PHYS_NET_NAME H_CPU1_MEMHOT_IN_LVC1_R_N
J 0
(-225 2367);
PAINT MONO (-225 2367);
DISPLAY INVISIBLE (-225 2367);
FORCEPROP 0 LAST SIG_NAME H_CPU1_MEMHOT_IN_LVC1_R_N
J 0
(-85 2335);
DISPLAY 0.680851 (-85 2335);
PAINT GREEN (-85 2335);
WIRE 16 -1 (-2550 1975)(-1525 1975);
FORCEPROP 0 LAST CDS_PHYS_NET_NAME H_CPU1_THERMTRIP_LVC1_N
J 0
(-2525 2017);
PAINT MONO (-2525 2017);
DISPLAY INVISIBLE (-2525 2017);
FORCEPROP 0 LAST SIG_NAME H_CPU1_THERMTRIP_LVC1_N
J 0
(-2560 1985);
DISPLAY 0.680851 (-2560 1985);
PAINT WHITE (-2560 1985);
WIRE 16 -1 (-225 2225)(725 2225);
FORCEPROP 0 LAST CDS_PHYS_NET_NAME H_CPU1_PROCHOT_LVC1_R_N
J 0
(-200 2267);
PAINT MONO (-200 2267);
DISPLAY INVISIBLE (-200 2267);
FORCEPROP 0 LAST SIG_NAME H_CPU1_PROCHOT_LVC1_R_N
J 0
(-85 2235);
DISPLAY 0.680851 (-85 2235);
PAINT GREEN (-85 2235);
WIRE 16 -1 (-225 3125)(900 3125);
FORCEPROP 0 LAST CDS_PHYS_NET_NAME PWRGD_DRAMPWRGD_CPU1_EF_R_LVC1
J 0
(-200 3167);
PAINT MONO (-200 3167);
DISPLAY INVISIBLE (-200 3167);
FORCEPROP 0 LAST SIG_NAME PWRGD_DRAMPWRGD_CPU1_EF_R_LVC1
J 0
(-135 3135);
DISPLAY 0.680851 (-135 3135);
PAINT GREEN (-135 3135);
WIRE 16 -1 (-225 3225)(900 3225);
FORCEPROP 0 LAST CDS_PHYS_NET_NAME PWRGD_DRAMPWRGD_CPU1_AB_R_LVC1
J 0
(-200 3267);
PAINT MONO (-200 3267);
DISPLAY INVISIBLE (-200 3267);
FORCEPROP 0 LAST SIG_NAME PWRGD_DRAMPWRGD_CPU1_AB_R_LVC1
J 0
(-135 3235);
DISPLAY 0.680851 (-135 3235);
PAINT GREEN (-135 3235);
WIRE 16 -1 (-225 3275)(900 3275);
FORCEPROP 0 LAST CDS_PHYS_NET_NAME PWRGD_DRAMPWRGD_CPU0_GH_R_LVC1
J 0
(-200 3317);
PAINT MONO (-200 3317);
DISPLAY INVISIBLE (-200 3317);
FORCEPROP 0 LAST SIG_NAME PWRGD_DRAMPWRGD_CPU0_GH_R_LVC1
J 0
(-135 3285);
DISPLAY 0.680851 (-135 3285);
PAINT GREEN (-135 3285);
WIRE 16 -1 (-225 3325)(900 3325);
FORCEPROP 0 LAST CDS_PHYS_NET_NAME PWRGD_DRAMPWRGD_CPU0_EF_R_LVC1
J 0
(-200 3367);
PAINT MONO (-200 3367);
DISPLAY INVISIBLE (-200 3367);
FORCEPROP 0 LAST SIG_NAME PWRGD_DRAMPWRGD_CPU0_EF_R_LVC1
J 0
(-135 3335);
DISPLAY 0.680851 (-135 3335);
PAINT GREEN (-135 3335);
WIRE 16 -1 (-225 3075)(900 3075);
FORCEPROP 0 LAST CDS_PHYS_NET_NAME PWRGD_DRAMPWRGD_CPU1_GH_R_LVC1
J 0
(-200 3117);
PAINT MONO (-200 3117);
DISPLAY INVISIBLE (-200 3117);
FORCEPROP 0 LAST SIG_NAME PWRGD_DRAMPWRGD_CPU1_GH_R_LVC1
J 0
(-135 3085);
DISPLAY 0.680851 (-135 3085);
PAINT GREEN (-135 3085);
WIRE 16 -1 (-225 3025)(900 3025);
FORCEPROP 0 LAST CDS_PHYS_NET_NAME PWRGD_DRAMPWRGD_CPU0_AB_R_LVC1
J 0
(-200 3067);
PAINT MONO (-200 3067);
DISPLAY INVISIBLE (-200 3067);
FORCEPROP 0 LAST SIG_NAME FM_BOARD_BMC_SKU_ID4
J 0
(-135 3035);
DISPLAY 0.680851 (-135 3035);
PAINT GREEN (-135 3035);
WIRE 16 -1 (-225 2975)(900 2975);
FORCEPROP 0 LAST CDS_PHYS_NET_NAME PWRGD_DRAMPWRGD_CPU0_CD_R_LVC1
J 0
(-200 3017);
PAINT MONO (-200 3017);
DISPLAY INVISIBLE (-200 3017);
FORCEPROP 0 LAST SIG_NAME FM_BOARD_BMC_SKU_ID3
J 0
(-135 2985);
DISPLAY 0.680851 (-135 2985);
PAINT GREEN (-135 2985);
WIRE 16 -1 (-225 2925)(900 2925);
FORCEPROP 0 LAST CDS_PHYS_NET_NAME PWRGD_DRAMPWRGD_CPU0_EF_R_LVC1
J 0
(-200 2967);
PAINT MONO (-200 2967);
DISPLAY INVISIBLE (-200 2967);
FORCEPROP 0 LAST SIG_NAME FM_BOARD_BMC_SKU_ID2
J 0
(-135 2935);
DISPLAY 0.680851 (-135 2935);
PAINT GREEN (-135 2935);
WIRE 16 -1 (-225 2775)(900 2775);
FORCEPROP 0 LAST CDS_PHYS_NET_NAME PWRGD_DRAMPWRGD_CPU1_CD_R_LVC1
J 0
(-200 2817);
PAINT MONO (-200 2817);
DISPLAY INVISIBLE (-200 2817);
FORCEPROP 0 LAST SIG_NAME FAB_BMC_REV_ID2
J 0
(-135 2785);
DISPLAY 0.680851 (-135 2785);
PAINT GREEN (-135 2785);
WIRE 16 -1 (-225 2825)(900 2825);
FORCEPROP 0 LAST CDS_PHYS_NET_NAME PWRGD_DRAMPWRGD_CPU1_AB_R_LVC1
J 0
(-200 2867);
PAINT MONO (-200 2867);
DISPLAY INVISIBLE (-200 2867);
FORCEPROP 0 LAST SIG_NAME FM_BOARD_BMC_SKU_ID0
J 0
(-135 2835);
DISPLAY 0.680851 (-135 2835);
PAINT GREEN (-135 2835);
WIRE 16 -1 (-225 2875)(900 2875);
FORCEPROP 0 LAST CDS_PHYS_NET_NAME PWRGD_DRAMPWRGD_CPU0_GH_R_LVC1
J 0
(-200 2917);
PAINT MONO (-200 2917);
DISPLAY INVISIBLE (-200 2917);
FORCEPROP 0 LAST SIG_NAME FM_BOARD_BMC_SKU_ID1
J 0
(-135 2885);
DISPLAY 0.680851 (-135 2885);
PAINT GREEN (-135 2885);
WIRE 16 -1 (-225 3175)(900 3175);
FORCEPROP 0 LAST CDS_PHYS_NET_NAME PWRGD_DRAMPWRGD_CPU1_CD_R_LVC1
J 0
(-200 3217);
PAINT MONO (-200 3217);
DISPLAY INVISIBLE (-200 3217);
FORCEPROP 0 LAST SIG_NAME PWRGD_DRAMPWRGD_CPU1_CD_R_LVC1
J 0
(-135 3185);
DISPLAY 0.680851 (-135 3185);
PAINT GREEN (-135 3185);
WIRE 16 -1 (-225 2725)(900 2725);
FORCEPROP 0 LAST CDS_PHYS_NET_NAME PWRGD_DRAMPWRGD_CPU1_EF_R_LVC1
J 0
(-200 2767);
PAINT MONO (-200 2767);
DISPLAY INVISIBLE (-200 2767);
FORCEPROP 0 LAST SIG_NAME FAB_BMC_REV_ID1
J 0
(-135 2735);
DISPLAY 0.680851 (-135 2735);
PAINT GREEN (-135 2735);
WIRE 16 -1 (-225 2675)(900 2675);
FORCEPROP 0 LAST CDS_PHYS_NET_NAME PWRGD_DRAMPWRGD_CPU1_GH_R_LVC1
J 0
(-200 2717);
PAINT MONO (-200 2717);
DISPLAY INVISIBLE (-200 2717);
FORCEPROP 0 LAST SIG_NAME FAB_BMC_REV_ID0
J 0
(-135 2685);
DISPLAY 0.680851 (-135 2685);
PAINT GREEN (-135 2685);
WIRE 16 -1 (-225 2375)(725 2375);
FORCEPROP 0 LAST CDS_PHYS_NET_NAME H_CPU0_MEMHOT_IN_LVC1_R_N
J 0
(-200 2417);
PAINT MONO (-200 2417);
DISPLAY INVISIBLE (-200 2417);
FORCEPROP 0 LAST SIG_NAME H_CPU0_MEMHOT_IN_LVC1_R_N
J 0
(-85 2385);
DISPLAY 0.680851 (-85 2385);
PAINT GREEN (-85 2385);
WIRE 16 -1 (-225 2275)(725 2275);
FORCEPROP 0 LAST CDS_PHYS_NET_NAME H_CPU0_PROCHOT_LVC1_R_N
J 0
(-200 2317);
PAINT MONO (-200 2317);
DISPLAY INVISIBLE (-200 2317);
FORCEPROP 0 LAST SIG_NAME H_CPU0_PROCHOT_LVC1_R_N
J 0
(-85 2285);
DISPLAY 0.680851 (-85 2285);
PAINT GREEN (-85 2285);
WIRE 16 -1 (-225 2175)(725 2175);
FORCEPROP 0 LAST CDS_PHYS_NET_NAME H_CPU_CATERR_LVC1_R_N
J 0
(-200 2217);
PAINT MONO (-200 2217);
DISPLAY INVISIBLE (-200 2217);
FORCEPROP 0 LAST SIG_NAME H_CPU_CATERR_LVC2_R2_N
J 0
(-85 2185);
DISPLAY 0.680851 (-85 2185);
PAINT WHITE (-85 2185);
WIRE 16 -1 (-225 2125)(725 2125);
FORCEPROP 0 LAST CDS_PHYS_NET_NAME FM_THERMTRIP_DLY_LVC1_R_N
J 0
(-200 2167);
PAINT MONO (-200 2167);
DISPLAY INVISIBLE (-200 2167);
FORCEPROP 0 LAST SIG_NAME FM_THERMTRIP_DLY_LVC1_R_N
J 0
(-85 2135);
DISPLAY 0.680851 (-85 2135);
PAINT GREEN (-85 2135);
WIRE 16 -1 (-225 2075)(725 2075);
FORCEPROP 0 LAST CDS_PHYS_NET_NAME H_CPU_NMI_LVC1_R_N
J 0
(-200 2117);
PAINT MONO (-200 2117);
DISPLAY INVISIBLE (-200 2117);
FORCEPROP 0 LAST SIG_NAME H_CPU_NMI_LVC1_R_N
J 0
(-85 2085);
DISPLAY 0.680851 (-85 2085);
PAINT GREEN (-85 2085);
WIRE 16 -1 (-225 2025)(725 2025);
FORCEPROP 0 LAST CDS_PHYS_NET_NAME H_CPU_RMCA_LVC1_R_N
J 0
(-200 2067);
PAINT MONO (-200 2067);
DISPLAY INVISIBLE (-200 2067);
FORCEPROP 0 LAST SIG_NAME H_CPU_RMCA_LVC2_R2_N
J 0
(-85 2035);
DISPLAY 0.680851 (-85 2035);
PAINT WHITE (-85 2035);
WIRE 16 -1 (-225 1975)(750 1975);
FORCEPROP 0 LAST CDS_PHYS_NET_NAME RST_CPU0_LVC1_R_N
J 0
(-200 2017);
PAINT MONO (-200 2017);
DISPLAY INVISIBLE (-200 2017);
FORCEPROP 0 LAST SIG_NAME RST_CPU0_LVC1_R_N
J 0
(-85 1985);
DISPLAY 0.680851 (-85 1985);
PAINT GREEN (-85 1985);
WIRE 16 -1 (-225 1925)(750 1925);
FORCEPROP 0 LAST CDS_PHYS_NET_NAME RST_CPU1_LVC1_R_N
J 0
(-200 1967);
PAINT MONO (-200 1967);
DISPLAY INVISIBLE (-200 1967);
FORCEPROP 0 LAST SIG_NAME RST_CPU1_LVC1_R_N
J 0
(-85 1935);
DISPLAY 0.680851 (-85 1935);
PAINT GREEN (-85 1935);
WIRE 16 -1 (-225 1875)(750 1875);
FORCEPROP 0 LAST CDS_PHYS_NET_NAME PWRGD_CPU0_LVC1_R
J 0
(-200 1917);
PAINT MONO (-200 1917);
DISPLAY INVISIBLE (-200 1917);
FORCEPROP 0 LAST SIG_NAME PWRGD_CPU0_LVC1_R
J 0
(-85 1885);
DISPLAY 0.680851 (-85 1885);
PAINT GREEN (-85 1885);
WIRE 16 -1 (-225 1825)(750 1825);
FORCEPROP 0 LAST CDS_PHYS_NET_NAME PWRGD_CPU1_LVC1_R
J 0
(-200 1867);
PAINT MONO (-200 1867);
DISPLAY INVISIBLE (-200 1867);
FORCEPROP 0 LAST SIG_NAME PWRGD_CPU1_LVC1_R
J 0
(-85 1835);
DISPLAY 0.680851 (-85 1835);
PAINT GREEN (-85 1835);
WIRE 16 -1 (-2550 2175)(-1525 2175);
FORCEPROP 0 LAST CDS_PHYS_NET_NAME H_CPU1_MEMHOT_OUT_LVC1_N
J 0
(-2525 2217);
PAINT MONO (-2525 2217);
DISPLAY INVISIBLE (-2525 2217);
FORCEPROP 0 LAST SIG_NAME H_CPU1_MEMHOT_OUT_LVC1_N
J 0
(-2560 2185);
DISPLAY 0.680851 (-2560 2185);
PAINT WHITE (-2560 2185);
WIRE 16 -1 (-2550 2075)(-1525 2075);
FORCEPROP 0 LAST CDS_PHYS_NET_NAME H_CPU1_MEMTRIP_LVC1_N
J 0
(-2525 2117);
PAINT MONO (-2525 2117);
DISPLAY INVISIBLE (-2525 2117);
FORCEPROP 0 LAST SIG_NAME H_CPU1_MEMTRIP_LVC1_N
J 0
(-2560 2085);
DISPLAY 0.680851 (-2560 2085);
PAINT WHITE (-2560 2085);
WIRE 16 -1 (-2550 2325)(-1525 2325);
FORCEPROP 0 LAST CDS_PHYS_NET_NAME H_CPU_ERR1_LVC1_N
J 0
(-2525 2367);
PAINT MONO (-2525 2367);
DISPLAY INVISIBLE (-2525 2367);
FORCEPROP 0 LAST SIG_NAME H_CPU_ERR1_LVC2_N
J 0
(-2560 2335);
DISPLAY 0.680851 (-2560 2335);
PAINT WHITE (-2560 2335);
WIRE 16 -1 (-2550 2375)(-1525 2375);
FORCEPROP 0 LAST CDS_PHYS_NET_NAME H_CPU_ERR0_LVC1_N
J 0
(-2525 2417);
PAINT MONO (-2525 2417);
DISPLAY INVISIBLE (-2525 2417);
FORCEPROP 0 LAST SIG_NAME H_CPU_ERR0_LVC2_N
J 0
(-2560 2385);
DISPLAY 0.680851 (-2560 2385);
PAINT WHITE (-2560 2385);
WIRE 16 -1 (-2525 2725)(-1525 2725);
FORCEPROP 0 LAST CDS_PHYS_NET_NAME RST_PLD_CPU1_DRAM_EF_N
J 0
(-2500 2767);
PAINT MONO (-2500 2767);
DISPLAY INVISIBLE (-2500 2767);
FORCEPROP 0 LAST SIG_NAME RST_PLD_CPU1_DRAM_EF_N
J 0
(-2510 2735);
DISPLAY 0.680851 (-2510 2735);
PAINT GREEN (-2510 2735);
WIRE 16 -1 (-375 -25)(825 -25);
FORCEPROP 0 LAST CDS_PHYS_NET_NAME JTAG_PLD_TDI_R
J 0
(-350 17);
PAINT MONO (-350 17);
DISPLAY INVISIBLE (-350 17);
FORCEPROP 0 LAST SIG_NAME JTAG_PLD_TDI_R
J 0
(-200 -15);
DISPLAY 0.680851 (-200 -15);
PAINT WHITE (-200 -15);
WIRE 16 -1 (-375 25)(825 25);
FORCEPROP 0 LAST CDS_PHYS_NET_NAME JTAG_PLD_TDO_R
J 0
(-350 67);
PAINT MONO (-350 67);
DISPLAY INVISIBLE (-350 67);
FORCEPROP 0 LAST SIG_NAME JTAG_PLD_TDO_R
J 0
(-200 35);
DISPLAY 0.680851 (-200 35);
PAINT WHITE (-200 35);
WIRE 16 -1 (-2550 1725)(-1525 1725);
FORCEPROP 0 LAST CDS_PHYS_NET_NAME PWRGD_CPUPWRGD_LVC1
J 0
(-2525 1767);
PAINT MONO (-2525 1767);
DISPLAY INVISIBLE (-2525 1767);
FORCEPROP 0 LAST SIG_NAME PWRGD_CPUPWRGD_LVC2_R1
J 0
(-2560 1735);
DISPLAY 0.680851 (-2560 1735);
PAINT WHITE (-2560 1735);
WIRE 16 -1 (-2550 2125)(-1525 2125);
FORCEPROP 0 LAST CDS_PHYS_NET_NAME H_CPU0_MEMTRIP_LVC1_N
J 0
(-2525 2167);
PAINT MONO (-2525 2167);
DISPLAY INVISIBLE (-2525 2167);
FORCEPROP 0 LAST SIG_NAME H_CPU0_MEMTRIP_LVC1_N
J 0
(-2560 2135);
DISPLAY 0.680851 (-2560 2135);
PAINT WHITE (-2560 2135);
WIRE 16 -1 (-2550 2275)(-1525 2275);
FORCEPROP 0 LAST CDS_PHYS_NET_NAME H_CPU_ERR2_LVC1_N
J 0
(-2525 2317);
PAINT MONO (-2525 2317);
DISPLAY INVISIBLE (-2525 2317);
FORCEPROP 0 LAST SIG_NAME H_CPU_ERR2_LVC2_N
J 0
(-2560 2285);
DISPLAY 0.680851 (-2560 2285);
PAINT WHITE (-2560 2285);
WIRE 16 -1 (-2525 2675)(-1525 2675);
FORCEPROP 0 LAST CDS_PHYS_NET_NAME RST_PLD_CPU1_DRAM_GH_N
J 0
(-2500 2717);
PAINT MONO (-2500 2717);
DISPLAY INVISIBLE (-2500 2717);
FORCEPROP 0 LAST SIG_NAME RST_PLD_CPU1_DRAM_GH_N
J 0
(-2510 2685);
DISPLAY 0.680851 (-2510 2685);
PAINT GREEN (-2510 2685);
FORCENOTE
20210902 MODIFY FOR GT
(-4325 3975) 0;
DISPLAY LEFT (-4325 3975);
DISPLAY 2.510638 (-4325 3975);
PAINT PINK (-4325 3975);
QUIT
